G04 ================== begin FILE IDENTIFICATION RECORD ==================*
G04 Layout Name:  12004-1.brd*
G04 Film Name:    DIF_REF_TOP*
G04 File Format:  Gerber RS274X*
G04 File Origin:  Cadence Allegro 16.2-S033*
G04 Origin Date:  Tue Oct 16 14:36:14 2012*
G04 *
G04 Layer:  BOARD GEOMETRY/OUTLINE*
G04 Layer:  BOARD GEOMETRY/DIF_REF_TOP*
G04 Layer:  BOARD GEOMETRY/PANEL_OUTLINE*
G04 *
G04 Offset:    (0.00 0.00)*
G04 Mirror:    No*
G04 Mode:      Positive*
G04 Rotation:  0*
G04 FullContactRelief:  No*
G04 UndefLineWidth:     6.00*
G04 ================== end FILE IDENTIFICATION RECORD ====================*
%FSLAX35Y35*MOIN*%
%IR0*IPPOS*OFA0.00000B0.00000*MIA0B0*SFA1.00000B1.00000*%
%ADD10C,.004*%
%ADD11C,.006*%
G75*
%LPD*%
G75*
G54D10*
G01X77453Y529374D02*
X78969Y530890D01*
G01X66497Y525105D02*
X67681Y526290D01*
G01D02*
G03X68100Y527300I-1010J1011D01*
G01D02*
Y529529D01*
G01D02*
G02X69944Y533984I6300J1D01*
G01D02*
X77387Y541427D01*
G01D02*
G02X81842Y543271I4454J-4456D01*
G01X69970Y525089D02*
G02X69400Y526465I1376J1376D01*
G01D02*
Y529529D01*
G01D02*
G02X70864Y533064I5000J0D01*
G01D02*
X78307Y540507D01*
G01X55470Y529198D02*
X56944Y530672D01*
G01D02*
G03X57267Y531452I-780J780D01*
G01D02*
G03X57300Y531800I-1831J349D01*
G01D02*
Y533200D01*
G01D02*
G02X58599Y536339I4439J1D01*
G01D02*
X67627Y545367D01*
G01D02*
G02X72082Y547211I4454J-4456D01*
G01D02*
X73211D01*
G01D02*
X73600Y547600D01*
G01D02*
X74711D01*
G01D02*
X75100Y547211D01*
G01D02*
X75991D01*
G01D02*
X76431Y547651D01*
G01D02*
X77491D01*
G01D02*
X77931Y547211D01*
G01D02*
X79163D01*
G01X59007Y529278D02*
G02X58600Y530261I983J983D01*
G01D02*
Y533200D01*
G01D02*
G02X59519Y535419I3138J0D01*
G01D02*
X68547Y544447D01*
G01D02*
G02X72082Y545911I3535J-3536D01*
G01D02*
X88752D01*
G01X44031Y524946D02*
X45284Y526198D01*
G01D02*
G03X45947Y527800I-1602J1601D01*
G01D02*
Y533176D01*
G01D02*
G02X47411Y536711I5000J0D01*
G01D02*
X62036Y551336D01*
G01D02*
G02X65571Y552800I3535J-3536D01*
G01D02*
X72186D01*
G01D02*
X72626Y553240D01*
G01D02*
X73826D01*
G01D02*
X74266Y552800D01*
G01D02*
X75466D01*
G01D02*
X75906Y553240D01*
G01D02*
X77091D01*
G01D02*
X77531Y552800D01*
G01D02*
X78683D01*
G01X47790Y524850D02*
G02X47247Y526161I1311J1311D01*
G01D02*
Y533176D01*
G01D02*
G02X48331Y535791I3699J-1D01*
G01D02*
X62956Y550416D01*
G01D02*
G02X65571Y551500I2616J-2615D01*
G01D02*
X89929D01*
G01X77292Y521666D02*
Y520400D01*
G01D02*
G03X77471Y519932I701J0D01*
G01D02*
X77719Y519657D01*
G01D02*
G03X78240Y519425I521J469D01*
G01D02*
X79375D01*
G01X77453Y525874D02*
X79093Y524233D01*
G01X78598Y521666D02*
X77292D01*
G01X66272Y517540D02*
Y516117D01*
G01D02*
G03X66721Y515033I1533J0D01*
G01D02*
G03X67216Y514828I495J495D01*
G01D02*
X68205D01*
G01D02*
G02X68700Y514623I0J-700D01*
G01D02*
X68720Y514603D01*
G01D02*
G02X68920Y514120I-483J-483D01*
G01D02*
Y513506D01*
G01D02*
G03X70234Y510330I4490J-2D01*
G01D02*
X70479Y510085D01*
G01D02*
G03X75019Y508205I4540J4542D01*
G01D02*
X78827D01*
G01X66497Y521605D02*
X68110Y519992D01*
G01D02*
G02X68315Y519497I-495J-495D01*
G01D02*
Y518240D01*
G01D02*
G02X67615Y517540I-700J0D01*
G01D02*
X66272D01*
G01X70227D02*
X70220Y517533D01*
G01D02*
Y513505D01*
G01D02*
G03X71154Y511250I3189J0D01*
G01D02*
X71399Y511005D01*
G01D02*
G03X75020Y509505I3621J3621D01*
G01D02*
X78826D01*
G01X69970Y521589D02*
G02X70227Y520969I-620J-620D01*
G01D02*
Y517540D01*
G01X55229Y521570D02*
Y519496D01*
G01D02*
G03X55929Y518796I700J0D01*
G01D02*
X57101D01*
G01D02*
G02X57801Y518096I0J-700D01*
G01D02*
Y514464D01*
G01D02*
G03X59779Y509685I6757J-2D01*
G01D02*
G03X73736Y503905I13956J13958D01*
G01D02*
X76867D01*
G01D02*
G02X77879Y503485I-1J-1430D01*
G01D02*
G03X78868Y502775I2661J2663D01*
G01X55470Y525698D02*
X56705Y524462D01*
G01D02*
G02X57119Y523464I-998J-999D01*
G01D02*
Y522318D01*
G01D02*
G02X56900Y521789I-748J0D01*
G01D02*
G02X56371Y521570I-529J529D01*
G01D02*
X55229D01*
G01X59232Y521602D02*
G03X59101Y521286I316J-316D01*
G01D02*
Y514463D01*
G01D02*
G03X60699Y510605I5456J0D01*
G01D02*
G03X73736Y505205I13037J13037D01*
G01D02*
X76868D01*
G01D02*
G02X78799Y504405I0J-2731D01*
G01X59007Y525778D02*
Y522145D01*
G01D02*
G03X59232Y521602I768J0D01*
G01X43905Y517250D02*
Y514448D01*
G01D02*
G03X44610Y513743I705J0D01*
G01D02*
X45956D01*
G01D02*
G02X46652Y513047I0J-696D01*
G01D02*
Y512306D01*
G01D02*
G03X48625Y507539I6740J-2D01*
G01D02*
X49779Y506385D01*
G01D02*
G03X65666Y499805I15887J15889D01*
G01D02*
X74594D01*
G01D02*
G02X76415Y499050I0J-2574D01*
G01D02*
G03X80199Y497484I3782J3785D01*
G01X44031Y521446D02*
X45471Y520006D01*
G01D02*
G02X45886Y519004I-1002J-1002D01*
G01D02*
Y518234D01*
G01D02*
G02X45666Y517704I-748J0D01*
G01D02*
X45549Y517587D01*
G01D02*
G02X44737Y517250I-813J812D01*
G01D02*
X43905D01*
G01X47952Y517237D02*
Y512305D01*
G01D02*
G03X49545Y508459I5439J0D01*
G01D02*
X50699Y507305D01*
G01D02*
G03X65667Y501105I14968J14968D01*
G01D02*
X74595D01*
G01D02*
G02X77335Y499970I0J-3875D01*
G01D02*
G03X80199Y498783I2865J2864D01*
G01X47790Y521350D02*
Y517628D01*
G01D02*
G03X47952Y517237I553J0D01*
G01X69569Y608021D02*
G02X70163Y608267I594J-594D01*
G01D02*
X75119D01*
G01D02*
X75118Y608268D01*
G01X69496Y611417D02*
X75119D01*
G01D02*
X75118Y611418D01*
G01X69569Y598159D02*
G02X71160Y598818I1591J-1591D01*
G01D02*
X75119D01*
G01D02*
X75118Y598819D01*
G01X69599Y601527D02*
X69966D01*
G01D02*
G03X70625Y601679I0J1506D01*
G01D02*
G02X71323Y601968I698J-698D01*
G01D02*
X75119D01*
G01D02*
X75118Y601969D01*
G01X69450Y573460D02*
X69611Y573621D01*
G01D02*
X75119D01*
G01D02*
X75118Y573622D01*
G01X69388Y576660D02*
X69499Y576771D01*
G01D02*
X75119D01*
G01D02*
X75118Y576772D01*
G01X69555Y564187D02*
X69569Y564173D01*
G01D02*
X75119D01*
G01D02*
X75118Y564174D01*
G01X69523Y567387D02*
X69588Y567322D01*
G01D02*
X75119D01*
G01D02*
X75118Y567323D01*
G01X69451Y691003D02*
G02X71209Y691731I1758J-1758D01*
G01D02*
X75119D01*
G01D02*
X75118Y691732D01*
G01X69474Y694403D02*
G02X70628Y694881I1154J-1154D01*
G01D02*
X75119D01*
G01D02*
X75118Y694882D01*
G01X69451Y681103D02*
G02X72300Y682283I2849J-2849D01*
G01D02*
X75119D01*
G01D02*
X75118Y682284D01*
G01X69451Y684303D02*
G03X70703Y684721I0J2084D01*
G01D02*
G02X72420Y685432I1717J-1717D01*
G01D02*
X75119D01*
G01D02*
X75118Y685433D01*
G01X69548Y726185D02*
G02X70012Y726377I464J-464D01*
G01D02*
X75117D01*
G01D02*
X75118Y726378D01*
G01X69472Y729385D02*
X69615Y729528D01*
G01D02*
X75118D01*
G01X69523Y715113D02*
G02X70001Y716269I1634J1D01*
G01D02*
X70228Y716495D01*
G01D02*
G02X71273Y716928I1045J-1045D01*
G01D02*
X75119D01*
G01D02*
X75118Y716929D01*
G01X69523Y718313D02*
Y719001D01*
G01D02*
G02X69762Y719578I816J0D01*
G01D02*
G02X70969Y720078I1207J-1207D01*
G01D02*
X75119D01*
G01D02*
X75118Y720079D01*
G01X124973Y324105D02*
X124388Y323521D01*
G01D02*
G03X123800Y322100I1421J-1420D01*
G01D02*
Y321766D01*
G01D02*
G03X124200Y320800I1366J0D01*
G01D02*
G03X157753Y306902I33553J33553D01*
G01Y305602D02*
G02X123280Y319880I-1J48752D01*
G01D02*
G02X122500Y321767I1887J1885D01*
G01D02*
Y322517D01*
G01D02*
G03X122205Y323229I-1007J0D01*
G01D02*
X121255Y324179D01*
G01X136317Y328206D02*
X135892Y328030D01*
G01D02*
G03X135280Y327417I435J-1047D01*
G01D02*
X135187Y327192D01*
G01D02*
G03X135100Y326757I1047J-436D01*
G01D02*
Y322529D01*
G01D02*
X135101Y322530D01*
G01D02*
G03X135900Y320600I2731J0D01*
G01D02*
G03X158157Y311381I22257J22257D01*
G01Y310081D02*
G02X134980Y319680I-2J32777D01*
G01D02*
G02X133800Y322530I2852J2850D01*
G01D02*
Y327161D01*
G01D02*
G03X133494Y327900I-1045J0D01*
G01D02*
G03X132755Y328206I-739J-739D01*
G01D02*
X132717D01*
G01X147553Y323992D02*
G03X146484Y322017I2784J-2784D01*
G01D02*
G03X146400Y321208I3853J-809D01*
G01D02*
Y319824D01*
G01D02*
G03X146700Y319100I1024J0D01*
G01D02*
G03X154143Y316017I7443J7443D01*
G01X143853Y324092D02*
X144720Y323224D01*
G01D02*
G02X145100Y322308I-916J-917D01*
G01D02*
Y319823D01*
G01D02*
G03X145780Y318180I2325J0D01*
G01D02*
G03X154142Y314717I8362J8364D01*
G01X125223Y331655D02*
G02X124141Y334267I2612J2612D01*
G01D02*
Y341005D01*
G01D02*
G03X120637Y349464I-11963J0D01*
G01X124973Y327605D02*
Y331405D01*
G01D02*
X125223Y331655D01*
G01X121005Y331729D02*
G03X122841Y336161I-4432J4432D01*
G01D02*
Y341004D01*
G01D02*
G03X119718Y348545I-10663J1D01*
G01X121255Y327679D02*
Y331479D01*
G01D02*
X121005Y331729D01*
G01X136467Y335856D02*
G02X135280Y338722I2866J2866D01*
G01D02*
Y341832D01*
G01D02*
G03X133665Y345734I-5518J2D01*
G01X136317Y331706D02*
Y335706D01*
G01D02*
X136467Y335856D01*
G01X132467D02*
G03X133980Y339509I-3653J3653D01*
G01D02*
Y341832D01*
G01D02*
G03X132745Y344814I-4217J0D01*
G01D02*
X115000Y362559D01*
G01X132717Y331706D02*
Y335606D01*
G01D02*
X132467Y335856D01*
G01X147560Y331731D02*
X147511Y331779D01*
G01D02*
G02X146526Y333910I2406J2405D01*
G01D02*
X146527D01*
G01D02*
G03X144783Y338118I-5946J1D01*
G01D02*
X144697Y338202D01*
G01D02*
X144000Y338900D01*
G01D02*
X142254Y340646D01*
G01D02*
G02X141079Y343483I2837J2837D01*
G01D02*
Y343484D01*
G01D02*
G03X141051Y344027I-5397J-6D01*
G01D02*
G03X139499Y347300I-5370J-542D01*
G01X147553Y327492D02*
Y331724D01*
G01D02*
X147560Y331731D01*
G01X143603Y331742D02*
X144841Y332979D01*
G01D02*
G03X145226Y333910I-931J930D01*
G01D02*
G03X143866Y337195I-4645J1D01*
G01D02*
X143780Y337280D01*
G01D02*
X141334Y339726D01*
G01D02*
G02X139778Y343482I3758J3757D01*
G01D02*
Y343483D01*
G01D02*
G03X139757Y343896I-4097J-1D01*
G01D02*
G03X138579Y346380I-4076J-412D01*
G01X143853Y327592D02*
Y331492D01*
G01D02*
X143603Y331742D01*
G01X150038Y343799D02*
G02X144282Y346182I-1J8140D01*
G01X133864Y398350D02*
X131894Y400320D01*
G01X133864Y402287D02*
X131894Y404257D01*
G01X137801Y398350D02*
X135831Y400320D01*
G01X137801Y402287D02*
X135831Y404257D01*
G01X102364Y398350D02*
X104334Y400320D01*
G01X102364Y402287D02*
X104334Y404257D01*
G01X108271Y400320D02*
X106301Y398350D01*
G01X108271Y404257D02*
X106301Y402287D01*
G01X145865Y398350D02*
X145675D01*
G01D02*
X143705Y400320D01*
G01X145865Y402287D02*
X145675D01*
G01D02*
X143705Y404257D01*
G01X149579Y398383D02*
X147642Y400320D01*
G01X149488Y402411D02*
X147642Y404257D01*
G01X112208Y400320D02*
X110238Y398350D01*
G01X112208Y404257D02*
X110238Y402287D01*
G01X116145Y400320D02*
X114175Y398350D01*
G01X116145Y404257D02*
X114175Y402287D01*
G01X122053Y398350D02*
X120083Y400320D01*
G01X122053Y402287D02*
X120083Y404257D01*
G01X125990Y398350D02*
X124020Y400320D01*
G01X125990Y402287D02*
X124020Y404257D01*
G01X129927Y398350D02*
X127957Y400320D01*
G01X129927Y402287D02*
X127957Y404257D01*
G01X141738Y398350D02*
X139768Y400320D01*
G01X141738Y402287D02*
X139768Y404257D01*
G01X120637Y349464D02*
X115597Y354504D01*
G01D02*
G02X104000Y382500I27996J27997D01*
G01D02*
Y387703D01*
G01D02*
G02X104334Y388509I1140J0D01*
G01X119718Y348545D02*
X119717Y348544D01*
G01D02*
X114677Y353584D01*
G01D02*
G02X102701Y382500I28917J28914D01*
G01D02*
X102700D01*
G01D02*
Y389656D01*
G01D02*
G02X103517Y391628I2790J-1D01*
G01D02*
X104334Y392446D01*
G01X133665Y345734D02*
X115920Y363479D01*
G01D02*
G02X107752Y383200I19721J19720D01*
G01D02*
Y387256D01*
G01D02*
G02X108271Y388509I1772J0D01*
G01X115000Y362559D02*
G02X106453Y383200I20642J20638D01*
G01D02*
X106452D01*
G01D02*
Y388055D01*
G01D02*
G02X108271Y392446I6210J0D01*
G01X154975Y374611D02*
X143781Y385805D01*
G01D02*
G02X143451Y386600I795J796D01*
G01D02*
Y387354D01*
G01D02*
X143497Y387400D01*
G01D02*
Y388007D01*
G01D02*
G02X143705Y388509I710J0D01*
G01X154055Y373691D02*
X142862Y384885D01*
G01D02*
G02X142151Y386599I1714J1715D01*
G01D02*
Y387354D01*
G01D02*
X142105Y387400D01*
G01D02*
Y388583D01*
G01D02*
G02X143705Y392446I5463J0D01*
G01X156225Y378375D02*
X148190Y386410D01*
G01D02*
G02X147642Y387733I1323J1323D01*
G01D02*
Y388509D01*
G01X155305Y377455D02*
X147480Y385280D01*
G01D02*
G02X146011Y388826I3546J3546D01*
G01D02*
Y389111D01*
G01D02*
G02X147642Y392446I5675J-709D01*
G01X139499Y347300D02*
X115679Y371120D01*
G01D02*
G02X111463Y381300I10180J10179D01*
G01D02*
Y387005D01*
G01D02*
G02X112000Y388300I1832J-1D01*
G01D02*
X112208Y388509D01*
G01X138579Y346380D02*
X114759Y370200D01*
G01D02*
G02X110164Y381300I11101J11097D01*
G01D02*
X110163D01*
G01D02*
Y388105D01*
G01D02*
G02X111787Y392024I5543J-1D01*
G01D02*
X112208Y392446D01*
G01X150038Y345099D02*
G02X145202Y347102I0J6839D01*
G01D02*
X119804Y372500D01*
G01D02*
G02X115579Y382700I10200J10200D01*
G01D02*
Y387143D01*
G01D02*
G02X116145Y388509I1932J0D01*
G01X144282Y346182D02*
X118884Y371580D01*
G01D02*
G02X114279Y382700I11120J11119D01*
G01D02*
Y388305D01*
G01D02*
G02X115888Y392188I5492J-1D01*
G01D02*
X116145Y392446D01*
G01X150464Y349483D02*
G02X147282Y350801I0J4500D01*
G01D02*
X122622Y375462D01*
G01D02*
G02X119499Y383000I7538J7539D01*
G01D02*
Y387099D01*
G01D02*
G02X120083Y388509I1994J0D01*
G01X150464Y348183D02*
G02X146362Y349881I-1J5801D01*
G01D02*
X121702Y374542D01*
G01D02*
G02X118200Y383000I8459J8456D01*
G01D02*
X118199D01*
G01D02*
Y387905D01*
G01D02*
G02X120078Y392441I6415J0D01*
G01D02*
X120083Y392446D01*
G01X149426Y354214D02*
X123996Y379644D01*
G01D02*
G02X123058Y381906I2262J2263D01*
G01D02*
Y386583D01*
G01D02*
G02X123740Y388228I2327J-1D01*
G01D02*
X124020Y388509D01*
G01X151687Y351976D02*
G02X148506Y353294I1J4500D01*
G01D02*
X123076Y378724D01*
G01D02*
G02X121758Y381906I3182J3182D01*
G01D02*
Y387283D01*
G01D02*
G02X123809Y392236I7004J1D01*
G01D02*
X124020Y392446D01*
G01X149940Y358960D02*
X128365Y380535D01*
G01D02*
G02X127047Y383717I3182J3182D01*
G01D02*
Y386126D01*
G01D02*
X127030Y386231D01*
G01D02*
G02X126999Y386605I2253J375D01*
G01D02*
G02X127668Y388220I2284J0D01*
G01D02*
X127957Y388509D01*
G01X149020Y358040D02*
X127445Y379615D01*
G01D02*
G02X125747Y383717I4103J4101D01*
G01D02*
Y386021D01*
G01D02*
G02X125710Y386316I3535J593D01*
G01D02*
G02X125699Y386667I3573J288D01*
G01D02*
Y386995D01*
G01D02*
G02X127957Y392446I7709J0D01*
G01X151798Y363303D02*
X132837Y382261D01*
G01D02*
G02X131519Y385443I3182J3182D01*
G01D02*
Y387604D01*
G01D02*
G02X131894Y388509I1280J0D01*
G01X150878Y362383D02*
X131917Y381341D01*
G01D02*
G02X130219Y385443I4103J4101D01*
G01D02*
Y388402D01*
G01D02*
G02X131894Y392446I5719J0D01*
G01X153397Y367003D02*
X136396Y384004D01*
G01D02*
G02X135456Y386274I2271J2270D01*
G01D02*
Y387604D01*
G01D02*
G02X135831Y388509I1280J0D01*
G01X152477Y366083D02*
X135476Y383084D01*
G01D02*
G02X134156Y386274I3191J3189D01*
G01D02*
Y388583D01*
G01D02*
G02X135703Y392318I5282J0D01*
G01D02*
X135831Y392446D01*
G01X154089Y370911D02*
X139803Y385197D01*
G01D02*
G02X139259Y386510I1314J1314D01*
G01D02*
Y387280D01*
G01D02*
G02X139768Y388509I1738J0D01*
G01X153169Y369991D02*
X138883Y384277D01*
G01D02*
G02X137959Y386509I2235J2232D01*
G01D02*
Y388583D01*
G01D02*
G02X139411Y392090I4959J1D01*
G01D02*
X139768Y392446D01*
G01X141738Y484968D02*
X139768Y482998D01*
G01X141738Y481031D02*
X139768Y479061D01*
G01X137801Y484968D02*
X135831Y482998D01*
G01X137801Y481031D02*
X135831Y479061D01*
G01X133864Y484968D02*
X131894Y482998D01*
G01X133864Y481031D02*
X131894Y479061D01*
G01X129927Y484968D02*
X127957Y482998D01*
G01X129927Y481031D02*
X127957Y479061D01*
G01X149620Y484976D02*
X147642Y482998D01*
G01X149504Y480923D02*
X147642Y479061D01*
G01X143705Y482998D02*
X145675Y484968D01*
G01X143705Y479061D02*
X145675Y481031D01*
G01X124020Y482998D02*
X125990Y484968D01*
G01X124020Y479061D02*
X125990Y481031D01*
G01X122053Y484968D02*
X120083Y482998D01*
G01X122053Y481031D02*
X120083Y479061D01*
G01X114175Y484968D02*
X116145Y482998D01*
G01X114175Y481031D02*
X116145Y479061D01*
G01X110238Y484968D02*
X112208Y482998D01*
G01X110238Y481031D02*
X112208Y479061D01*
G01X106301Y484968D02*
X108271Y482998D01*
G01Y479061D02*
X106301Y481031D01*
G01X102364Y484968D02*
X104334Y482998D01*
G01X102364Y481031D02*
X104334Y479061D01*
G01X98427Y484968D02*
X100397Y482998D01*
G01X98427Y481031D02*
X100397Y479061D01*
G01X94490Y484968D02*
X96460Y482998D01*
G01X94490Y481031D02*
X96460Y479061D01*
G01X144206Y529584D02*
X144572Y529950D01*
G01D02*
G03X145342Y531809I-1859J1859D01*
G01D02*
Y536600D01*
G01D02*
X144902Y537040D01*
G01D02*
Y538240D01*
G01D02*
X145342Y538680D01*
G01D02*
Y539880D01*
G01D02*
X144902Y540320D01*
G01D02*
Y541520D01*
G01D02*
X145342Y541960D01*
G01D02*
Y543160D01*
G01D02*
X144902Y543600D01*
G01D02*
Y544800D01*
G01D02*
X145342Y545240D01*
G01D02*
Y546440D01*
G01D02*
X144902Y546880D01*
G01D02*
Y548080D01*
G01D02*
X145342Y548520D01*
G01D02*
Y601800D01*
G01X147678Y529618D02*
X147459Y529838D01*
G01D02*
G02X146642Y531809I1971J1972D01*
G01D02*
Y715290D01*
G01X133163Y525553D02*
X133338Y525728D01*
G01D02*
G03X134299Y528048I-2320J2320D01*
G01D02*
Y535400D01*
G01D02*
X133859Y535840D01*
G01D02*
Y537040D01*
G01D02*
X134299Y537480D01*
G01D02*
Y538680D01*
G01D02*
X133859Y539120D01*
G01D02*
Y540320D01*
G01D02*
X134299Y540760D01*
G01D02*
Y541960D01*
G01D02*
X133859Y542400D01*
G01D02*
Y543600D01*
G01D02*
X134299Y544040D01*
G01D02*
Y545240D01*
G01D02*
X133859Y545680D01*
G01D02*
Y546880D01*
G01D02*
X134299Y547320D01*
G01D02*
Y548520D01*
G01D02*
X133859Y548960D01*
G01D02*
Y550160D01*
G01D02*
X134299Y550600D01*
G01D02*
Y707492D01*
G01X136663Y525453D02*
G02X135599Y528022I2569J2569D01*
G01D02*
Y707492D01*
G01X153091Y509212D02*
X140665Y496786D01*
G01D02*
X140532Y496652D01*
G01D02*
G03X139768Y494809I1843J-1844D01*
G01X154011Y508293D02*
X142012Y496294D01*
G01D02*
G03X141463Y494969I1325J-1325D01*
G01D02*
Y494964D01*
G01D02*
G02X141442Y494471I-5787J0D01*
G01D02*
G02X139768Y490872I-5766J493D01*
G01X154018Y515654D02*
X137026Y498662D01*
G01D02*
G03X136165Y496582I2082J-2080D01*
G01D02*
Y495615D01*
G01D02*
G02X135831Y494809I-1140J0D01*
G01X154842Y514638D02*
X137946Y497742D01*
G01D02*
G03X137465Y496581I1161J-1161D01*
G01D02*
Y494462D01*
G01D02*
G02X136082Y491123I-4722J0D01*
G01D02*
X135831Y490872D01*
G01X143962Y522038D02*
G03X143757Y521543I495J-495D01*
G01D02*
Y520036D01*
G01D02*
G03X144457Y519336I700J0D01*
G01D02*
X145813D01*
G01D02*
G02X146328Y519109I0J-698D01*
G01D02*
X146396Y519041D01*
G01D02*
G02X146514Y518756I-285J-285D01*
G01D02*
Y518014D01*
G01D02*
G02X146508Y517885I-1400J0D01*
G01D02*
G02X146228Y517288I-969J90D01*
G01D02*
X134901Y505961D01*
G01D02*
G03X132219Y499484I6480J-6477D01*
G01D02*
Y495594D01*
G01D02*
G02X131894Y494809I-1110J0D01*
G01X144206Y526084D02*
X145688Y524602D01*
G01D02*
Y522738D01*
G01D02*
G02X144988Y522038I-700J0D01*
G01D02*
X143962D01*
G01X147904Y522037D02*
X147814Y521947D01*
G01D02*
Y517976D01*
G01D02*
G02X147148Y516368I-2274J0D01*
G01D02*
X135821Y505041D01*
G01D02*
G03X133519Y499483I5559J-5558D01*
G01D02*
Y494795D01*
G01D02*
G02X131894Y490872I-5548J0D01*
G01X147678Y526118D02*
Y522263D01*
G01D02*
X147904Y522037D01*
G01X132913Y517903D02*
Y516657D01*
G01D02*
G03X133093Y516221I616J-1D01*
G01D02*
X133440Y515874D01*
G01D02*
G03X134007Y515639I567J567D01*
G01D02*
X134803D01*
G01D02*
G02X135071Y515586I1J-700D01*
G01D02*
G02X135235Y515450I-141J-337D01*
G01D02*
G02X135620Y514354I-948J-949D01*
G01D02*
X135607Y514239D01*
G01D02*
G02X135376Y513758I-801J89D01*
G01D02*
X135061Y513443D01*
G01D02*
Y513442D01*
G01D02*
X132193Y510574D01*
G01D02*
X131474Y509854D01*
G01D02*
G03X128563Y502827I7029J-7028D01*
G01D02*
Y496272D01*
G01D02*
G02X127957Y494809I-2069J0D01*
G01X133163Y522053D02*
X134925Y520290D01*
G01D02*
G02X135130Y519795I-495J-495D01*
G01D02*
Y518603D01*
G01D02*
G02X134430Y517903I-700J0D01*
G01D02*
X132913D01*
G01X136913D02*
Y514328D01*
G01D02*
G02X136296Y512838I-2107J0D01*
G01D02*
X133113Y509655D01*
G01D02*
X132394Y508935D01*
G01D02*
G03X132393Y508934I6109J-6110D01*
G01D02*
G03X129863Y502826I6110J-6109D01*
G01D02*
Y494783D01*
G01D02*
G02X128445Y491361I-4840J1D01*
G01D02*
X127957Y490872D01*
G01X136663Y521953D02*
Y518507D01*
G01D02*
G03X136913Y517903I854J0D01*
G01X156243Y503902D02*
X147987Y495646D01*
G01D02*
G03X147642Y494813I833J-833D01*
G01D02*
Y494809D01*
G01X149223Y494056D02*
G02X147820Y491050I-4836J427D01*
G01D02*
X147642Y490872D01*
G01X153694Y505653D02*
X144157Y496116D01*
G01D02*
G03X143705Y495025I1091J-1091D01*
G01D02*
Y494809D01*
G01X154994Y505114D02*
X146039Y496159D01*
G01D02*
G03X145469Y494783I1376J-1376D01*
G01D02*
G02X143951Y491118I-5183J0D01*
G01D02*
X143705Y490872D01*
G01X122044Y529612D02*
X123726Y531294D01*
G01D02*
G03X124201Y532441I-1147J1147D01*
G01D02*
Y536322D01*
G01D02*
G02X125959Y540566I6002J0D01*
G01D02*
X126673Y541280D01*
G01D02*
G03X129630Y548419I-7139J7139D01*
G01D02*
Y711099D01*
G01X125501Y529596D02*
Y536322D01*
G01D02*
G02X126877Y539644I4698J0D01*
G01D02*
X127593Y540360D01*
G01D02*
G03X130930Y548419I-8060J8058D01*
G01D02*
Y711099D01*
G01X110786Y525501D02*
X112615Y527330D01*
G01D02*
G03X113246Y528853I-1523J1523D01*
G01D02*
Y534075D01*
G01D02*
G02X115414Y539313I7406J3D01*
G01D02*
X122673Y546571D01*
G01D02*
G03X125850Y554241I-7670J7670D01*
G01D02*
Y699979D01*
G01X114546Y525502D02*
Y534076D01*
G01D02*
G02X116334Y538393I6105J0D01*
G01D02*
X123593Y545651D01*
G01D02*
G03X127150Y554241I-8591J8589D01*
G01D02*
Y699979D01*
G01X99797Y529396D02*
X101415Y531014D01*
G01D02*
G03X102030Y532499I-1485J1485D01*
G01D02*
Y532728D01*
G01D02*
G02X103120Y535361I3725J0D01*
G01D02*
X120221Y552461D01*
G01D02*
G03X121803Y556280I-3819J3819D01*
G01D02*
Y677026D01*
G01X103330Y529515D02*
Y532727D01*
G01D02*
G02X104040Y534441I2424J0D01*
G01D02*
X121141Y551541D01*
G01D02*
G03X123103Y556279I-4740J4738D01*
G01D02*
Y677026D01*
G01X88606Y525183D02*
X90226Y526803D01*
G01D02*
X90497Y527075D01*
G01D02*
G03X90857Y527909I-870J870D01*
G01D02*
G03X90858Y527945I-1229J52D01*
G01D02*
Y528121D01*
G01D02*
G02X91668Y530078I2769J0D01*
G01D02*
X116902Y555311D01*
G01D02*
G03X118077Y558148I-2837J2837D01*
G01X92158Y525184D02*
Y528120D01*
G01D02*
G02X92588Y529158I1468J0D01*
G01D02*
X117822Y554391D01*
G01D02*
G03X119377Y558148I-3758J3756D01*
G01X121801Y522079D02*
X121673Y521951D01*
G01D02*
G03X121468Y521456I495J-495D01*
G01D02*
Y520100D01*
G01D02*
G03X122168Y519400I700J0D01*
G01D02*
X123606D01*
G01D02*
G02X124035Y519223I1J-606D01*
G01D02*
X124212Y519045D01*
G01D02*
G02X124417Y518550I-495J-495D01*
G01D02*
Y495767D01*
G01D02*
G02X124391Y495505I-1355J2D01*
G01D02*
G02X124020Y494809I-1329J262D01*
G01X122044Y526112D02*
Y526111D01*
G01D02*
X123672Y524483D01*
G01D02*
G02X123877Y523988I-495J-495D01*
G01D02*
Y522935D01*
G01D02*
G02X123672Y522440I-700J0D01*
G01D02*
X123516Y522284D01*
G01D02*
G02X123021Y522079I-495J495D01*
G01D02*
X121801D01*
G01X125750Y522071D02*
X125717Y522038D01*
G01D02*
Y494969D01*
G01D02*
G02X124020Y490872I-5794J0D01*
G01X125501Y526096D02*
Y522320D01*
G01D02*
X125750Y522071D01*
G01X110657Y517857D02*
Y516082D01*
G01D02*
G03X111063Y515102I1386J0D01*
G01D02*
X111291Y514874D01*
G01D02*
G03X111786Y514669I495J495D01*
G01D02*
X112709D01*
G01D02*
G02X113180Y514474I0J-666D01*
G01D02*
G02X113375Y514003I-471J-471D01*
G01D02*
Y513205D01*
G01D02*
G03X115055Y509149I5736J0D01*
G01D02*
X117199Y507005D01*
G01D02*
G02X120662Y498645I-8360J-8360D01*
G01D02*
Y495678D01*
G01D02*
G02X120457Y495183I-700J0D01*
G01D02*
X120083Y494809D01*
G01X110786Y522001D02*
X112005Y520782D01*
G01D02*
G02X112647Y519232I-1550J-1550D01*
G01D02*
Y518557D01*
G01D02*
G02X111947Y517857I-700J0D01*
G01D02*
X110657D01*
G01X114675Y517858D02*
Y513204D01*
G01D02*
G03X115975Y510069I4435J2D01*
G01D02*
X118119Y507925D01*
G01D02*
G02X120595Y504478I-9280J-9279D01*
G01D02*
G02X121962Y498646I-11756J-5832D01*
G01D02*
Y495388D01*
G01D02*
X121942Y495391D01*
G01D02*
X121962Y494683D01*
G01D02*
G02X120596Y491385I-4664J0D01*
G01D02*
X120083Y490872D01*
G01X114546Y522002D02*
G02X114675Y521691I-311J-311D01*
G01D02*
Y517858D01*
G01X99435Y521826D02*
Y520671D01*
G01D02*
G03X100063Y520043I628J0D01*
G01D02*
X101498D01*
G01D02*
G02X102464Y519077I0J-966D01*
G01D02*
Y518505D01*
G01D02*
G03X104870Y512694I8217J-1D01*
G01D02*
X114355Y503209D01*
G01D02*
G02X116470Y498104I-5104J-5105D01*
G01D02*
Y495689D01*
G01D02*
X116448Y495667D01*
G01D02*
X116454Y495232D01*
G01D02*
G02X116307Y494971I-539J132D01*
G01D02*
X116145Y494809D01*
G01X99797Y525896D02*
X101234Y524459D01*
G01D02*
G02X101386Y524231I-495J-495D01*
G01D02*
X101408Y524178D01*
G01D02*
G02X101432Y524059I-288J-120D01*
G01D02*
Y522709D01*
G01D02*
G02X101227Y522214I-700J0D01*
G01D02*
X101044Y522031D01*
G01D02*
G02X100549Y521826I-495J495D01*
G01D02*
X99435D01*
G01X103454Y521857D02*
G02X103764Y521109I-748J-748D01*
G01D02*
Y518505D01*
G01D02*
G03X105790Y513614I6917J0D01*
G01D02*
X115275Y504129D01*
G01D02*
G02X117770Y498105I-6025J-6024D01*
G01D02*
Y495150D01*
G01D02*
X117756Y495136D01*
G01D02*
X117770Y494183D01*
G01D02*
G02X116578Y491305I-4070J0D01*
G01D02*
X116145Y490872D01*
G01X103330Y526015D02*
Y521981D01*
G01D02*
X103454Y521857D01*
G01X88412Y517603D02*
Y516320D01*
G01D02*
G03X88744Y515725I699J0D01*
G01D02*
X88910Y515600D01*
G01D02*
G03X89331Y515460I420J560D01*
G01D02*
X90470D01*
G01D02*
G02X91026Y515186I1J-700D01*
G01D02*
X91173Y514994D01*
G01D02*
G03X91748Y513621I3708J746D01*
G01D02*
G03X91855Y513507I2106J1870D01*
G01D02*
G03X93847Y512683I1991J1992D01*
G01D02*
X96336D01*
G01D02*
G02X101162Y510684I0J-6826D01*
G01D02*
X106257Y505589D01*
G01D02*
X107512Y504333D01*
G01D02*
Y504334D01*
G01D02*
X111482Y500363D01*
G01D02*
G02X112563Y497755I-2606J-2608D01*
G01D02*
Y495666D01*
G01D02*
G02X112488Y495247I-1212J1D01*
G01D02*
G02X112479Y495224I-1133J430D01*
G01D02*
G02X112208Y494809I-1129J441D01*
G01X88606Y521683D02*
X90153Y520136D01*
G01D02*
G02X90358Y519641I-495J-495D01*
G01D02*
Y518303D01*
G01D02*
G02X89658Y517603I-700J0D01*
G01D02*
X88412D01*
G01X92400D02*
Y515738D01*
G01D02*
G03X92775Y514427I2482J1D01*
G01D02*
G03X93847Y513983I1072J1072D01*
G01D02*
X96336D01*
G01D02*
G02X102082Y511603I0J-8126D01*
G01D02*
X112402Y501283D01*
G01D02*
G02X113863Y497756I-3527J-3527D01*
G01D02*
Y494683D01*
G01D02*
G02X112338Y491003I-5205J1D01*
G01D02*
X112208Y490872D01*
G01X92158Y521684D02*
G02X92400Y521100I-584J-584D01*
G01D02*
Y517603D01*
G01X78969Y530890D02*
X79133Y531053D01*
G01D02*
G03X79817Y532706I-1653J1652D01*
G01D02*
Y534373D01*
G01D02*
G02X80700Y536506I3018J0D01*
G01D02*
X81069Y536875D01*
G01D02*
G02X84046Y538107I2976J-2978D01*
G01D02*
X91938D01*
G01D02*
G03X96240Y539889I0J6084D01*
G01D02*
X111608Y555257D01*
G01D02*
G03X113361Y559489I-4232J4232D01*
G01X81117Y529310D02*
Y534372D01*
G01D02*
G02X81620Y535586I1717J0D01*
G01D02*
X81989Y535955D01*
G01D02*
G02X84046Y536807I2057J-2057D01*
G01D02*
X91939D01*
G01D02*
G03X97160Y538969I0J7385D01*
G01D02*
X112528Y554337D01*
G01D02*
G03X114661Y559489I-5152J5151D01*
G01X81842Y543271D02*
X91474D01*
G01D02*
G03X96066Y545174I-2J6497D01*
G01D02*
X107036Y556144D01*
G01D02*
G03X108500Y559679I-3536J3535D01*
G01X78307Y540507D02*
G02X81842Y541971I3535J-3536D01*
G01D02*
X91475D01*
G01D02*
G03X96986Y544254I-2J7798D01*
G01D02*
X107956Y555224D01*
G01D02*
G03X109800Y559679I-4456J4454D01*
G01X79163Y547211D02*
X79603Y547651D01*
G01D02*
X80663D01*
G01D02*
X81103Y547211D01*
G01D02*
X82443D01*
G01D02*
X82883Y547651D01*
G01D02*
X83943D01*
G01D02*
X84383Y547211D01*
G01D02*
X85708D01*
G01D02*
X86148Y547651D01*
G01D02*
X87208D01*
G01D02*
X87648Y547211D01*
G01D02*
X88753D01*
G01D02*
G03X95517Y550013I-1J9567D01*
G01D02*
X101218Y555714D01*
G01D02*
X101227Y555725D01*
G01D02*
X101261Y555759D01*
G01D02*
G03X102916Y559753I-3994J3995D01*
G01X88752Y545911D02*
G03X96437Y549093I2J10868D01*
G01D02*
X102128Y554784D01*
G01D02*
G03X102147Y554805I-202J201D01*
G01D02*
X102181Y554839D01*
G01D02*
G03X104216Y559752I-4914J4913D01*
G01X78683Y552800D02*
X79123Y553240D01*
G01D02*
X80263D01*
G01D02*
X80703Y552800D01*
G01D02*
X81903D01*
G01D02*
X82343Y553240D01*
G01D02*
X83543D01*
G01D02*
X83983Y552800D01*
G01D02*
X85183D01*
G01D02*
X85623Y553240D01*
G01D02*
X86808D01*
G01D02*
X87248Y552800D01*
G01D02*
X89929D01*
G01D02*
G03X93464Y554264I0J5000D01*
G01D02*
X95002Y555802D01*
G01D02*
G03X96466Y559337I-3536J3535D01*
G01X89929Y551500D02*
G03X94384Y553344I1J6300D01*
G01D02*
X95922Y554882D01*
G01D02*
G03X97766Y559337I-4456J4454D01*
G01X79375Y519425D02*
G02X80075Y518725I0J-700D01*
G01D02*
Y515911D01*
G01D02*
G03X81943Y511399I6380J-1D01*
G01D02*
X83274Y510068D01*
G01D02*
G03X85895Y508983I2621J2623D01*
G01D02*
X95175D01*
G01D02*
G02X99253Y507294I0J-5767D01*
G01D02*
X107039Y499507D01*
G01D02*
X107375Y499172D01*
G01D02*
G02X108571Y496283I-2889J-2888D01*
G01D02*
Y495533D01*
G01D02*
G02X108271Y494809I-1024J0D01*
G01X79093Y524233D02*
G02X79298Y523738I-495J-495D01*
G01D02*
Y522366D01*
G01D02*
G02X78598Y521666I-700J0D01*
G01X81375Y521698D02*
Y515911D01*
G01D02*
G03X82863Y512319I5080J0D01*
G01D02*
X84194Y510988D01*
G01D02*
G03X85896Y510283I1702J1702D01*
G01D02*
X95175D01*
G01D02*
G02X100172Y508214I1J-7067D01*
G01D02*
X108294Y500092D01*
G01D02*
G02X109871Y496283I-3808J-3808D01*
G01D02*
Y494735D01*
G01D02*
G02X108271Y490872I-5463J0D01*
G01X81117Y525810D02*
G02X81375Y525187I-623J-623D01*
G01D02*
Y521698D01*
G01X78827Y508205D02*
G02X80079Y507685I-2J-1772D01*
G01D02*
G03X81965Y506331I5075J5078D01*
G01D02*
G03X85155Y505583I3191J6431D01*
G01D02*
X94483D01*
G01D02*
G02X96943Y504564I0J-3479D01*
G01D02*
X104323Y497184D01*
G01D02*
G02X104720Y496478I-1062J-1062D01*
G01D02*
G02X104722Y496471I-1442J-416D01*
G01D02*
Y495746D01*
G01D02*
G02X104334Y494809I-1325J0D01*
G01X78826Y509505D02*
G02X80999Y508605I0J-3073D01*
G01D02*
G03X85156Y506883I4157J4157D01*
G01D02*
X94263D01*
G01D02*
G02X98018Y505327I-1J-5311D01*
G01D02*
X98163Y505183D01*
G01D02*
X105210Y498136D01*
G01D02*
G02X105975Y496785I-2060J-2058D01*
G01D02*
G02X106063Y496077I-2824J-710D01*
G01D02*
Y495046D01*
G01D02*
G02X104334Y490872I-5903J0D01*
G01X78868Y502775D02*
G03X80541Y502383I1673J3373D01*
G01D02*
X93463D01*
G01D02*
G02X95102Y501704I-1J-2320D01*
G01D02*
X95103Y501702D01*
G01D02*
X95243Y501564D01*
G01D02*
X100026Y496781D01*
G01D02*
G02X100397Y495885I-896J-896D01*
G01D02*
Y494809D01*
G01X78799Y504405D02*
G03X80542Y503683I1743J1743D01*
G01D02*
X93464D01*
G01D02*
G02X96021Y502624I-1J-3620D01*
G01D02*
X96161Y502485D01*
G01D02*
X101145Y497501D01*
G01D02*
G02X102063Y495285I-2216J-2216D01*
G01D02*
Y494383D01*
G01D02*
G02X100758Y491234I-4454J1D01*
G01D02*
X100397Y490872D01*
G01X80199Y497484D02*
Y497483D01*
G01D02*
X94514D01*
G01D02*
G02X95963Y496883I0J-2049D01*
G01D02*
X96255Y496591D01*
G01D02*
G02X96460Y496096I-495J-495D01*
G01D02*
Y494809D01*
G01X80199Y498783D02*
X94514D01*
G01D02*
G02X96883Y497802I1J-3349D01*
G01D02*
X97246Y497439D01*
G01D02*
G02X98346Y494783I-2657J-2656D01*
G01D02*
G02X96914Y491326I-4889J0D01*
G01D02*
X96460Y490872D01*
G01X145342Y601800D02*
X144902Y602240D01*
G01D02*
Y603440D01*
G01D02*
X145342Y603880D01*
G01D02*
Y605080D01*
G01D02*
X144902Y605520D01*
G01D02*
Y606720D01*
G01D02*
X145342Y607160D01*
G01D02*
Y715291D01*
G01X118077Y558148D02*
Y666052D01*
G01X119377Y558148D02*
Y666052D01*
G01X113361Y559489D02*
Y586683D01*
G01D02*
X112921Y587123D01*
G01D02*
Y588263D01*
G01D02*
X113361Y588703D01*
G01D02*
Y589903D01*
G01D02*
X112921Y590343D01*
G01D02*
Y591543D01*
G01D02*
X113361Y591983D01*
G01D02*
Y593183D01*
G01D02*
X112921Y593623D01*
G01D02*
Y594808D01*
G01D02*
X113361Y595248D01*
G01D02*
Y599268D01*
G01D02*
G03X111897Y602803I-5000J0D01*
G01D02*
X105364Y609336D01*
G01D02*
G03X101829Y610800I-3535J-3536D01*
G01D02*
X90676D01*
G01D02*
G03X89522Y610322I0J-1632D01*
G01D02*
G02X88366Y609843I-1156J1155D01*
G01D02*
X85000D01*
G01X114661Y559489D02*
Y599268D01*
G01D02*
G03X112817Y603723I-6300J1D01*
G01D02*
X106284Y610256D01*
G01D02*
G03X101829Y612100I-4454J-4456D01*
G01D02*
X90931D01*
G01D02*
G02X89854Y612546I0J1523D01*
G01D02*
G03X88777Y612992I-1077J-1077D01*
G01D02*
X85000D01*
G01X108500Y559679D02*
Y575286D01*
G01D02*
X108060Y575726D01*
G01D02*
Y576926D01*
G01D02*
X108500Y577366D01*
G01D02*
Y578566D01*
G01D02*
X108060Y579006D01*
G01D02*
Y580191D01*
G01D02*
X108500Y580631D01*
G01D02*
Y581783D01*
G01D02*
X108060Y582223D01*
G01D02*
Y583363D01*
G01D02*
X108500Y583803D01*
G01D02*
Y585003D01*
G01D02*
X108060Y585443D01*
G01D02*
Y586643D01*
G01D02*
X108500Y587083D01*
G01D02*
Y593529D01*
G01D02*
G03X107036Y597064I-5000J0D01*
G01D02*
X104264Y599836D01*
G01D02*
G03X100729Y601300I-3535J-3536D01*
G01D02*
X89941D01*
G01D02*
G03X88847Y600847I0J-1548D01*
G01D02*
G02X87753Y600394I-1094J1095D01*
G01D02*
X85000D01*
G01X109800Y559679D02*
Y593529D01*
G01D02*
G03X107956Y597984I-6300J1D01*
G01D02*
X105184Y600756D01*
G01D02*
G03X100729Y602600I-4454J-4456D01*
G01D02*
X90268D01*
G01D02*
G02X89128Y603072I0J1613D01*
G01D02*
G03X87988Y603544I-1140J-1141D01*
G01D02*
X85000D01*
G01X102916Y559753D02*
Y567913D01*
G01D02*
G03X101452Y571448I-5000J0D01*
G01D02*
X98190Y574710D01*
G01D02*
G03X94655Y576174I-3535J-3536D01*
G01D02*
X90565D01*
G01D02*
G03X89385Y575685I0J-1668D01*
G01D02*
G02X88207Y575197I-1178J1178D01*
G01D02*
X85000D01*
G01X104216Y559752D02*
Y567913D01*
G01D02*
G03X102372Y572368I-6300J1D01*
G01D02*
X99110Y575630D01*
G01D02*
G03X94655Y577474I-4454J-4456D01*
G01D02*
X90343D01*
G01D02*
G02X89290Y577910I0J1490D01*
G01D02*
G03X88235Y578347I-1055J-1055D01*
G01D02*
X85000D01*
G01X96466Y559337D02*
Y562663D01*
G01D02*
G03X95382Y565278I-3699J-1D01*
G01D02*
X95044Y565616D01*
G01D02*
G03X92429Y566700I-2616J-2615D01*
G01D02*
X89773D01*
G01D02*
G03X88624Y566224I0J-1625D01*
G01D02*
G02X87475Y565748I-1149J1149D01*
G01D02*
X85000D01*
G01X97766Y559337D02*
Y562664D01*
G01D02*
G03X96302Y566198I-5000J-1D01*
G01D02*
X95964Y566536D01*
G01D02*
G03X92429Y568000I-3535J-3536D01*
G01D02*
X89735D01*
G01D02*
G02X88651Y568449I0J1533D01*
G01D02*
G03X87567Y568898I-1084J-1084D01*
G01D02*
X85000D01*
G01X121803Y677026D02*
G03X120339Y680561I-5000J0D01*
G01D02*
X108164Y692736D01*
G01D02*
G03X104629Y694200I-3535J-3536D01*
G01D02*
X101017D01*
G01D02*
X100577Y693760D01*
G01D02*
X99437D01*
G01D02*
X98997Y694200D01*
G01D02*
X97797D01*
G01D02*
X97357Y693760D01*
G01D02*
X96157D01*
G01D02*
X95717Y694200D01*
G01D02*
X94517D01*
G01D02*
X94077Y693760D01*
G01D02*
X92892D01*
G01D02*
X92452Y694200D01*
G01D02*
X89531D01*
G01D02*
G03X88453Y693754I0J-1526D01*
G01D02*
X88336Y693637D01*
G01D02*
G02X87541Y693307I-796J794D01*
G01D02*
X85000D01*
G01X123103Y677026D02*
G03X121259Y681481I-6300J1D01*
G01D02*
X109084Y693656D01*
G01D02*
G03X104629Y695500I-4454J-4456D01*
G01D02*
X89977D01*
G01D02*
G02X88821Y695979I0J1634D01*
G01D02*
G03X87667Y696457I-1154J-1154D01*
G01D02*
X85000D01*
G01X118077Y666052D02*
G03X116613Y669587I-5000J0D01*
G01D02*
X110521Y675679D01*
G01D02*
X109899D01*
G01D02*
X109093Y676485D01*
G01D02*
Y677107D01*
G01D02*
X108244Y677956D01*
G01D02*
X107622D01*
G01D02*
X106774Y678804D01*
G01D02*
Y679427D01*
G01D02*
X105925Y680275D01*
G01D02*
X105303D01*
G01D02*
X104465Y681113D01*
G01D02*
Y681735D01*
G01D02*
X102864Y683336D01*
G01D02*
G03X99329Y684800I-3535J-3536D01*
G01D02*
X90066D01*
G01D02*
G03X88929Y684329I0J-1608D01*
G01D02*
G02X87792Y683858I-1137J1137D01*
G01D02*
X85000D01*
G01X119377Y666052D02*
G03X117533Y670507I-6300J1D01*
G01D02*
X103784Y684256D01*
G01D02*
G03X99329Y686100I-4454J-4456D01*
G01D02*
X89942D01*
G01D02*
G02X88846Y686554I0J1550D01*
G01D02*
G03X87750Y687008I-1096J-1096D01*
G01D02*
X85000D01*
G01X145342Y715291D02*
G02X153595Y735216I28180J-1D01*
G01X146642Y715290D02*
G02X154515Y734297I26880J0D01*
G01X134299Y707492D02*
X134300D01*
G01D02*
G02X146145Y736091I40445J1D01*
G01D02*
X146471Y736418D01*
G01D02*
X200136Y790083D01*
G01X135599Y707492D02*
G02X147065Y735172I39146J-1D01*
G01D02*
X147392Y735500D01*
G01D02*
X201056Y789164D01*
G01X129630Y711099D02*
G03X128166Y714634I-5000J0D01*
G01D02*
X115413Y727387D01*
G01D02*
G03X111878Y728851I-3535J-3536D01*
G01D02*
X100045D01*
G01D02*
X99605Y728411D01*
G01D02*
X98420D01*
G01D02*
X97980Y728851D01*
G01D02*
X96828D01*
G01D02*
X96388Y728411D01*
G01D02*
X95140D01*
G01D02*
X94700Y728851D01*
G01D02*
X90286D01*
G01D02*
G03X89202Y728402I0J-1533D01*
G01D02*
G02X88118Y727953I-1084J1084D01*
G01D02*
X85000D01*
G01X130930Y711099D02*
G03X129086Y715554I-6300J1D01*
G01D02*
X116333Y728307D01*
G01D02*
G03X111878Y730151I-4454J-4456D01*
G01D02*
X90821D01*
G01D02*
G02X89674Y730626I0J1622D01*
G01D02*
G03X88525Y731102I-1149J-1149D01*
G01D02*
X85000D01*
G01X125850Y699979D02*
G03X124386Y703514I-5000J0D01*
G01D02*
X109864Y718036D01*
G01D02*
G03X106329Y719500I-3535J-3536D01*
G01D02*
X103700D01*
G01D02*
X103200Y719000D01*
G01D02*
X102200D01*
G01D02*
X101700Y719500D01*
G01D02*
X100645D01*
G01D02*
X100205Y719060D01*
G01D02*
X99020D01*
G01D02*
X98580Y719500D01*
G01D02*
X97428D01*
G01D02*
X96988Y719060D01*
G01D02*
X95740D01*
G01D02*
X95300Y719500D01*
G01D02*
X89704D01*
G01D02*
G03X88502Y719002I0J-1700D01*
G01D02*
G02X87300Y718504I-1202J1202D01*
G01D02*
X85000D01*
G01X127150Y699979D02*
G03X125306Y704434I-6300J1D01*
G01D02*
X110784Y718956D01*
G01D02*
G03X106329Y720800I-4454J-4456D01*
G01D02*
X89604D01*
G01D02*
G02X88573Y721227I0J1458D01*
G01D02*
G03X87542Y721654I-1031J-1031D01*
G01D02*
X85000D01*
G01X157753Y306902D02*
X516485D01*
G01X634531Y305602D02*
X157753D01*
G01X158157Y311381D02*
X518665D01*
G01X629910Y310081D02*
X158157D01*
G01X154143Y316017D02*
X461600D01*
G01X154142Y314717D02*
X625446D01*
G01X158445Y328198D02*
X157998Y327751D01*
G01D02*
X157100Y326160D01*
G01D02*
G03X158345Y323155I4253J2D01*
G01D02*
X160025Y321475D01*
G01D02*
G03X163207Y320157I3182J3182D01*
G01D02*
X510940D01*
G01X621100Y318857D02*
X163207D01*
G01D02*
G02X159105Y320555I-1J5801D01*
G01D02*
X157425Y322235D01*
G01D02*
G02X155800Y326054I3924J3925D01*
G01D02*
X155799D01*
G01D02*
G03X154845Y328298I-3260J-61D01*
G01X169385Y332263D02*
X168709Y331586D01*
G01D02*
G03X168300Y330600I986J-987D01*
G01D02*
Y328536D01*
G01D02*
G03X169032Y326768I2501J0D01*
G01D02*
X170488Y325312D01*
G01D02*
G03X172256Y324580I1768J1769D01*
G01D02*
X509176D01*
G01X165885Y332263D02*
X166806Y331342D01*
G01D02*
G02X167000Y330874I-467J-468D01*
G01D02*
Y328536D01*
G01D02*
G03X168112Y325848I3802J-1D01*
G01D02*
X169568Y324392D01*
G01D02*
G03X172256Y323280I2687J2690D01*
G01D02*
X618700D01*
G01X180438Y336503D02*
X180394Y336460D01*
G01D02*
G03X179500Y334300I2160J-2159D01*
G01D02*
Y331873D01*
G01D02*
G03X180400Y329700I3073J0D01*
G01D02*
G03X182573Y328800I2173J2173D01*
G01D02*
X500540D01*
G01X176898Y336463D02*
X177896Y335465D01*
G01D02*
G02X178200Y334731I-734J-734D01*
G01D02*
Y331873D01*
G01D02*
G03X179480Y328780I4374J-1D01*
G01D02*
G03X182573Y327500I3092J3094D01*
G01D02*
X614500D01*
G01X191557Y340639D02*
G03X190623Y338716I2310J-2310D01*
G01D02*
Y337813D01*
G01D02*
G03X191355Y336045I2501J0D01*
G01D02*
X193468Y333932D01*
G01D02*
G03X195236Y333200I1768J1769D01*
G01D02*
X381560D01*
G01X188047Y340699D02*
X188896Y339851D01*
G01D02*
G02X189300Y338874I-977J-976D01*
G01D02*
X189323Y338851D01*
G01D02*
Y337813D01*
G01D02*
G03X190435Y335125I3802J-1D01*
G01D02*
X192548Y333012D01*
G01D02*
G03X195236Y331900I2687J2690D01*
G01D02*
X611000D01*
G01X202638Y344799D02*
G03X201600Y342293I2506J-2506D01*
G01D02*
Y340536D01*
G01D02*
G03X202332Y338768I2501J0D01*
G01D02*
X202848Y338252D01*
G01D02*
G03X204616Y337520I1768J1769D01*
G01D02*
X550044D01*
G01X199138Y344799D02*
X199332Y344605D01*
G01D02*
G02X200300Y342268I-2337J-2337D01*
G01D02*
Y340536D01*
G01D02*
G03X201412Y337848I3802J-1D01*
G01D02*
X201928Y337332D01*
G01D02*
G03X204616Y336220I2687J2690D01*
G01D02*
X550044D01*
G01X212500Y345854D02*
Y344173D01*
G01D02*
G03X213400Y342000I3073J0D01*
G01D02*
G03X214849Y341400I1449J1449D01*
G01D02*
X430060D01*
G01X211200Y346562D02*
Y344174D01*
G01D02*
G03X212480Y341080I4374J-2D01*
G01D02*
G03X214849Y340100I2367J2370D01*
G01D02*
X508002D01*
G01X158631Y335850D02*
G02X157241Y339206I3356J3356D01*
G01D02*
Y340001D01*
G01D02*
G03X155825Y343311I-4571J2D01*
G01D02*
G03X150388Y345099I-5434J-7365D01*
G01D02*
X150038D01*
G01X158445Y331698D02*
Y335664D01*
G01D02*
X158631Y335850D01*
G01X154602Y335814D02*
G03X155941Y339047I-3233J3233D01*
G01D02*
Y340002D01*
G01D02*
G03X154983Y342315I-3271J0D01*
G01D02*
G03X150388Y343800I-4595J-6368D01*
G01D02*
Y343799D01*
G01D02*
X150038D01*
G01X154845Y331798D02*
Y335571D01*
G01D02*
X154602Y335814D01*
G01X169635Y339913D02*
X169610Y339939D01*
G01D02*
G02X168300Y343100I3161J3162D01*
G01D02*
Y345101D01*
G01D02*
G03X167086Y348032I-4146J0D01*
G01X169385Y335763D02*
Y339663D01*
G01D02*
X169635Y339913D01*
G01X165635D02*
X165712Y339989D01*
G01D02*
G03X167000Y343100I-3111J3110D01*
G01D02*
Y345100D01*
G01D02*
G03X166166Y347112I-2846J-1D01*
G01X165885Y335763D02*
Y339663D01*
G01D02*
X165635Y339913D01*
G01X180688Y344153D02*
G02X179300Y345541I0J1388D01*
G01X180438Y340003D02*
Y343903D01*
G01D02*
X180688Y344153D01*
G01X176688D02*
X177700Y345165D01*
G01D02*
X178000Y345541D01*
G01X176898Y339963D02*
Y343943D01*
G01D02*
X176688Y344153D01*
G01X191557Y344139D02*
Y348039D01*
G01X188047Y344199D02*
Y348049D01*
G01X213780Y348944D02*
G03X212500Y345854I3090J-3090D01*
G01X210180Y348944D02*
X210237Y348887D01*
G01D02*
G02X211200Y346562I-2325J-2325D01*
G01X149583Y398383D02*
X149579D01*
G01X149488Y402114D02*
Y402411D01*
G01X225699Y373293D02*
X158157D01*
G01D02*
G02X154975Y374611I0J4500D01*
G01X225698Y371993D02*
X158157D01*
G01D02*
G02X154055Y373691I-1J5801D01*
G01X227837Y377057D02*
X159407D01*
G01D02*
G02X156225Y378375I0J4500D01*
G01X227838Y375757D02*
X159407D01*
G01D02*
G02X155305Y377455I-1J5801D01*
G01X167086Y348032D02*
G03X163579Y349483I-3504J-3507D01*
G01D02*
X150464D01*
G01X166166Y347112D02*
G03X163580Y348183I-2586J-2586D01*
G01D02*
X150464D01*
G01X179300Y345541D02*
Y348776D01*
G01D02*
G03X174800Y353276I-4500J0D01*
G01D02*
X151688D01*
G01D02*
G02X149426Y354214I1J3200D01*
G01X178000Y345541D02*
Y348776D01*
G01D02*
G03X174800Y351976I-3200J0D01*
G01D02*
X151687D01*
G01X191807Y348289D02*
X191402Y348694D01*
G01D02*
G02X190482Y351182I2243J2243D01*
G01D02*
G03X190500Y351652I-6038J467D01*
G01D02*
Y352650D01*
G01D02*
G03X189520Y355020I-3349J3D01*
G01D02*
X189093Y355447D01*
G01D02*
G03X184796Y357565I-5268J-5270D01*
G01D02*
X184795D01*
G01D02*
G03X183622Y357642I-1176J-8943D01*
G01D02*
X153122D01*
G01D02*
G02X149940Y358960I0J4500D01*
G01X191557Y348039D02*
X191807Y348289D01*
G01X187807D02*
G03X189200Y351652I-3363J3363D01*
G01D02*
Y352651D01*
G01D02*
G03X188600Y354100I-2049J0D01*
G01D02*
X188173Y354527D01*
G01D02*
G03X184626Y356276I-4349J-4349D01*
G01D02*
G03X183621Y356342I-1007J-7654D01*
G01D02*
X153122D01*
G01D02*
G02X149020Y358040I-1J5801D01*
G01X188047Y348049D02*
X187807Y348289D01*
G01X202888Y352449D02*
G02X201800Y355076I2627J2627D01*
G01D02*
Y357394D01*
G01D02*
G03X200920Y359520I-3008J0D01*
G01D02*
G03X194965Y361985I-5952J-5955D01*
G01D02*
X154980D01*
G01D02*
G02X151798Y363303I0J4500D01*
G01X202638Y348299D02*
Y352199D01*
G01D02*
X202888Y352449D01*
G01X198888D02*
G03X200500Y356341I-3892J3892D01*
G01D02*
Y357393D01*
G01D02*
G03X200000Y358600I-1707J0D01*
G01D02*
G03X194966Y360685I-5034J-5034D01*
G01D02*
X154980D01*
G01D02*
G02X150878Y362383I-1J5801D01*
G01X199138Y348299D02*
Y352199D01*
G01D02*
X198888Y352449D01*
G01X214030Y356594D02*
X213432Y357192D01*
G01D02*
G02X212683Y359000I1808J1808D01*
G01D02*
Y359357D01*
G01D02*
G03X210733Y364066I-6661J0D01*
G01D02*
X210432Y364367D01*
G01D02*
G03X207250Y365685I-3182J-3182D01*
G01D02*
X156579D01*
G01D02*
G02X153397Y367003I0J4500D01*
G01X213780Y352444D02*
Y356344D01*
G01D02*
X214030Y356594D01*
G01X209930D02*
X210457Y357122D01*
G01D02*
G03X211383Y359356I-2234J2235D01*
G01D02*
G03X209813Y363146I-5360J0D01*
G01D02*
X209512Y363447D01*
G01D02*
G03X207250Y364385I-2263J-2262D01*
G01D02*
X156579D01*
G01D02*
G02X152477Y366083I-1J5801D01*
G01X210180Y352444D02*
Y356344D01*
G01D02*
X209930Y356594D01*
G01X219400Y369593D02*
X157271D01*
G01D02*
G02X154089Y370911I0J4500D01*
G01X219400Y368293D02*
X157271D01*
G01D02*
G02X153169Y369991I-1J5801D01*
G01X193016Y485443D02*
X199013D01*
G01D02*
X200788Y483668D01*
G01X189516Y485443D02*
X185316D01*
G01D02*
X185266Y485393D01*
G01D02*
X183949Y486710D01*
G01X157486Y484968D02*
X155516Y482998D01*
G01X157508Y480990D02*
X155579Y479061D01*
G01D02*
X155516D01*
G01X153586Y485118D02*
Y485005D01*
G01D02*
X151579Y482998D01*
G01X153601Y480894D02*
X151768Y479061D01*
G01D02*
X151579D01*
G01X149620Y485149D02*
Y484976D01*
G01X149594Y480923D02*
X149504D01*
G01X193016Y489543D02*
X195243D01*
G01D02*
X199618Y493918D01*
G01D02*
X200788D01*
G01X183949Y486710D02*
X180657D01*
G01D02*
X178417Y488949D01*
G01D02*
X177651Y489716D01*
G01D02*
X173770D01*
G01D02*
X171264Y487210D01*
G01D02*
Y486935D01*
G01X189516Y489543D02*
X189466Y489593D01*
G01D02*
X185266D01*
G01D02*
X183683Y488010D01*
G01D02*
X181196D01*
G01D02*
X178190Y491016D01*
G01D02*
X171408D01*
G01D02*
X171264Y490872D01*
G01X166180Y529696D02*
G03X167316Y532439I-2743J2743D01*
G01D02*
Y539821D01*
G01D02*
X166899Y540238D01*
G01D02*
Y541221D01*
G01D02*
X167316Y541638D01*
G01D02*
Y542621D01*
G01D02*
X166899Y543038D01*
G01D02*
Y544021D01*
G01D02*
X167316Y544438D01*
G01D02*
Y545421D01*
G01D02*
X166899Y545838D01*
G01D02*
Y546821D01*
G01D02*
X167316Y547238D01*
G01D02*
Y548221D01*
G01D02*
X166899Y548638D01*
G01D02*
Y549621D01*
G01D02*
X167316Y550038D01*
G01D02*
Y551021D01*
G01D02*
X166899Y551438D01*
G01D02*
Y552421D01*
G01D02*
X167316Y552838D01*
G01D02*
Y553821D01*
G01D02*
X166899Y554238D01*
G01D02*
Y555221D01*
G01D02*
X167316Y555638D01*
G01D02*
Y721897D01*
G01X169812Y529697D02*
G02X168616Y532584I2887J2887D01*
G01D02*
Y721896D01*
G01X155181Y525492D02*
G03X156317Y528235I-2743J2743D01*
G01D02*
Y542055D01*
G01D02*
X155877Y542495D01*
G01D02*
Y543695D01*
G01D02*
X156317Y544135D01*
G01D02*
Y545335D01*
G01D02*
X155877Y545775D01*
G01D02*
Y546975D01*
G01D02*
X156317Y547415D01*
G01D02*
Y548615D01*
G01D02*
X155877Y549055D01*
G01D02*
Y550255D01*
G01D02*
X156317Y550695D01*
G01D02*
Y551750D01*
G01D02*
X155877Y552190D01*
G01D02*
Y553390D01*
G01D02*
X156317Y553830D01*
G01D02*
Y555030D01*
G01D02*
X155877Y555470D01*
G01D02*
Y556670D01*
G01X158691Y525443D02*
G02X157617Y528036I2593J2593D01*
G01D02*
Y716728D01*
G01X165955Y522020D02*
G03X165763Y521556I465J-464D01*
G01D02*
Y520037D01*
G01D02*
G03X166463Y519337I700J0D01*
G01D02*
X167283D01*
G01D02*
G02X168363Y518889I-1J-1528D01*
G01D02*
X168528Y518725D01*
G01D02*
G02X168666Y518113I-1289J-612D01*
G01D02*
Y517019D01*
G01D02*
G02X168659Y516861I-1946J7D01*
G01D02*
G02X168096Y515643I-1939J157D01*
G01D02*
X167025Y514572D01*
G01D02*
G02X161547Y512303I-5478J5478D01*
G01D02*
X160554D01*
G01D02*
G03X153091Y509212I-1J-10553D01*
G01X166180Y526196D02*
X167019Y525356D01*
G01D02*
G02X167817Y523431I-1925J-1926D01*
G01D02*
Y522720D01*
G01D02*
G02X167117Y522020I-700J0D01*
G01D02*
X165955D01*
G01X170037D02*
Y517744D01*
G01D02*
G02X168623Y514330I-4828J0D01*
G01D02*
X167945Y513652D01*
G01D02*
G02X161547Y511003I-6397J6399D01*
G01D02*
X160554D01*
G01D02*
G03X154011Y508293I0J-9253D01*
G01X169812Y526197D02*
Y522245D01*
G01D02*
X170037Y522020D01*
G01X154924Y517879D02*
Y517841D01*
G01D02*
G02X154018Y515654I-3093J0D01*
G01X155181Y521992D02*
X156422Y520751D01*
G01D02*
G02X156727Y520015I-736J-736D01*
G01D02*
Y518631D01*
G01D02*
G02X155975Y517879I-752J0D01*
G01D02*
X154924D01*
G01X158917Y517830D02*
G03X157408Y517205I0J-2134D01*
G01D02*
X155025Y514822D01*
G01D02*
X154842Y514638D01*
G01X158691Y521943D02*
G02X158917Y521397I-546J-546D01*
G01D02*
Y517830D01*
G01X210563Y529653D02*
X211321Y530412D01*
G01D02*
G03X211754Y531456I-1042J1044D01*
G01D02*
Y533733D01*
G01D02*
G02X213701Y538436I6650J1D01*
G01D02*
X274012Y598747D01*
G01X214163Y529553D02*
X213615Y530100D01*
G01D02*
G02X213054Y531456I1356J1355D01*
G01D02*
Y533733D01*
G01D02*
G02X214621Y537516I5350J0D01*
G01D02*
X274932Y597827D01*
G01X199363Y525453D02*
Y527117D01*
G01D02*
G02X200444Y528198I1081J0D01*
G01D02*
G03X201222Y528520I0J1101D01*
G01D02*
X201358Y528656D01*
G01D02*
X201663Y529392D01*
G01D02*
Y534495D01*
G01D02*
G02X203922Y539949I7713J0D01*
G01D02*
X203927Y539960D01*
G01D02*
X270112Y606144D01*
G01X202963Y525453D02*
Y534496D01*
G01D02*
X202964Y534495D01*
G01D02*
G02X204659Y538838I6412J0D01*
G01D02*
X204839Y539032D01*
G01D02*
X271468Y605661D01*
G01X188363Y529753D02*
X188798Y530188D01*
G01D02*
G03X189300Y531400I-1212J1212D01*
G01D02*
Y534700D01*
G01D02*
G02X190349Y537234I3583J1D01*
G01D02*
X190658Y537542D01*
G01D02*
X280522Y627406D01*
G01X191863Y529753D02*
X190872Y530745D01*
G01D02*
G02X190600Y531400I655J656D01*
G01D02*
Y534700D01*
G01D02*
G02X191268Y536311I2279J-1D01*
G01D02*
X191428Y536472D01*
G01D02*
X281442Y626486D01*
G01X177324Y525477D02*
G03X178368Y527997I-2520J2520D01*
G01D02*
Y530428D01*
G01D02*
G02X179580Y533357I4142J2D01*
G01D02*
X286999Y640776D01*
G01X180845Y525461D02*
X180748Y525557D01*
G01D02*
G02X179668Y528166I2609J2608D01*
G01D02*
Y530428D01*
G01D02*
G02X180500Y532437I2841J0D01*
G01D02*
X287900Y639837D01*
G01X210313Y522003D02*
X211527Y520789D01*
G01D02*
G02X211892Y519908I-881J-881D01*
G01D02*
Y514986D01*
G01D02*
G02X210634Y511949I-4295J0D01*
G01D02*
X205781Y507096D01*
G01D02*
G02X201892Y505485I-3889J3889D01*
G01D02*
X184075D01*
G01D02*
G03X179786Y503709I0J-6067D01*
G01D02*
X177808Y501731D01*
G01D02*
G02X172550Y499553I-5258J5258D01*
G01D02*
X160851D01*
G01D02*
G03X159258Y498893I0J-2253D01*
G01D02*
X155758Y495393D01*
G01D02*
G03X155516Y494809I584J-584D01*
G01X210563Y526153D02*
X211582Y525134D01*
G01D02*
G02X212362Y523251I-1883J-1883D01*
G01D02*
Y523018D01*
G01D02*
G02X212197Y522620I-563J0D01*
G01D02*
X211785Y522208D01*
G01D02*
G02X211290Y522003I-495J495D01*
G01D02*
X210313D01*
G01X214413Y521903D02*
X213739Y521230D01*
G01D02*
G03X213192Y519908I1322J-1321D01*
G01D02*
Y514986D01*
G01D02*
G02X211554Y511029I-5595J-1D01*
G01D02*
X206702Y506177D01*
G01D02*
G02X206701Y506176I-4716J4715D01*
G01D02*
G02X201893Y504185I-4808J4810D01*
G01D02*
X184076D01*
G01D02*
G03X180706Y502789I0J-4766D01*
G01D02*
X178728Y500811D01*
G01D02*
G02X172550Y498253I-6177J6178D01*
G01D02*
X160852D01*
G01D02*
G03X160178Y497973I1J-952D01*
G01D02*
X159069Y496864D01*
G01D02*
X158475Y496271D01*
G01D02*
X158082Y495878D01*
G01D02*
G03X157778Y495144I734J-734D01*
G01D02*
Y494583D01*
G01D02*
G02X156753Y492110I-3498J1D01*
G01D02*
X155516Y490872D01*
G01X214163Y526053D02*
Y522153D01*
G01D02*
X214413Y521903D01*
G01X199113Y517803D02*
X200210Y516707D01*
G01D02*
G02X200752Y515397I-1310J-1309D01*
G01D02*
Y513826D01*
G01D02*
G02X200167Y512414I-1997J0D01*
G01D02*
X198760Y511007D01*
G01D02*
G02X196773Y510184I-1987J1987D01*
G01D02*
X189565D01*
G01D02*
G03X188132Y509591I0J-2028D01*
G01D02*
X188130Y509589D01*
G01D02*
G02X187805Y509323I-1497J1497D01*
G01D02*
G02X186633Y508969I-1172J1763D01*
G01D02*
X183542D01*
G01D02*
G03X178205Y506759I0J-7549D01*
G01D02*
X176089Y504643D01*
G01D02*
G02X172733Y503253I-3356J3356D01*
G01D02*
X161829D01*
G01D02*
G03X157843Y501602I0J-5637D01*
G01D02*
X151953Y495712D01*
G01D02*
G03X151579Y494809I903J-903D01*
G01X199363Y521953D02*
Y518407D01*
G01D02*
G02X199113Y517803I-854J0D01*
G01X203213D02*
X202932Y517523D01*
G01D02*
G03X202052Y515397I2126J-2125D01*
G01D02*
Y513826D01*
G01D02*
G02X201087Y511494I-3297J-1D01*
G01D02*
X199680Y510087D01*
G01D02*
G02X196772Y508884I-2906J2908D01*
G01D02*
X189566D01*
G01D02*
G03X189052Y508671I0J-727D01*
G01D02*
X189050Y508669D01*
G01D02*
G02X186632Y507669I-2416J2418D01*
G01D02*
X183543D01*
G01D02*
G03X179125Y505839I0J-6248D01*
G01D02*
X177009Y503723D01*
G01D02*
G02X172732Y501953I-4275J4277D01*
G01D02*
X161688D01*
G01D02*
G03X158863Y500783I0J-3995D01*
G01D02*
X153678Y495598D01*
G01D02*
G03X153254Y494574I1024J-1024D01*
G01D02*
Y494383D01*
G01D02*
G02X151956Y491249I-4432J0D01*
G01D02*
X151579Y490872D01*
G01X202963Y521953D02*
Y518407D01*
G01D02*
G03X203213Y517803I854J0D01*
G01X188113Y522003D02*
X188918Y521198D01*
G01D02*
G02X189714Y519276I-1922J-1922D01*
G01D02*
Y517263D01*
G01D02*
G02X189109Y515801I-2067J-1D01*
G01D02*
X188575Y515268D01*
G01D02*
X186599Y513292D01*
G01D02*
G02X183149Y511863I-3450J3450D01*
G01D02*
X181512D01*
G01D02*
G03X177230Y510090I-1J-6054D01*
G01D02*
X176596Y509455D01*
G01D02*
X175238Y508097D01*
G01D02*
G02X169215Y505602I-6023J6023D01*
G01D02*
X167085D01*
G01D02*
X167084Y505603D01*
G01D02*
X160165D01*
G01D02*
G03X156373Y504033I-1J-5362D01*
G01D02*
X156243Y503902D01*
G01X188363Y526253D02*
X189622Y524994D01*
G01D02*
G02X190254Y523468I-1526J-1526D01*
G01D02*
Y522701D01*
G01D02*
G02X190050Y522207I-698J-1D01*
G01D02*
X190049Y522206D01*
G01D02*
G02X189557Y522003I-492J495D01*
G01D02*
X188113D01*
G01X192113D02*
G03X191014Y519350I2653J-2653D01*
G01D02*
Y517263D01*
G01D02*
G02X190028Y514881I-3367J-1D01*
G01D02*
X189494Y514348D01*
G01D02*
X189025Y513878D01*
G01D02*
X187519Y512372D01*
G01D02*
G02X183148Y510563I-4369J4371D01*
G01D02*
X181512D01*
G01D02*
G03X178150Y509171I-1J-4754D01*
G01D02*
X177516Y508536D01*
G01D02*
X176158Y507177D01*
G01D02*
G02X169216Y504302I-6942J6944D01*
G01D02*
X166546D01*
G01D02*
X166545Y504303D01*
G01D02*
X160165D01*
G01D02*
G03X157294Y503115I0J-4062D01*
G01D02*
X157165Y502984D01*
G01D02*
X151016Y496835D01*
G01D02*
Y496830D01*
G01D02*
X149665Y495479D01*
G01D02*
G03X149223Y494412I1067J-1067D01*
G01D02*
Y494056D01*
G01X191863Y526253D02*
Y522607D01*
G01D02*
G03X192113Y522003I854J0D01*
G01X177099Y517848D02*
Y516192D01*
G01D02*
G02X176240Y515333I-859J0D01*
G01D02*
X175679D01*
G01D02*
G03X173919Y514605I-1J-2488D01*
G01D02*
X171419Y512104D01*
G01D02*
X171420D01*
G01D02*
X171413Y512098D01*
G01D02*
G02X164665Y509303I-6748J6748D01*
G01D02*
X159964D01*
G01D02*
G03X155483Y507448I-2J-6334D01*
G01D02*
X155140Y507104D01*
G01D02*
X153694Y505658D01*
G01D02*
Y505653D01*
G01X177324Y521977D02*
X178604Y520696D01*
G01D02*
G02X179115Y519464I-1232J-1233D01*
G01D02*
Y518762D01*
G01D02*
G02X178910Y518267I-700J0D01*
G01D02*
X178696Y518053D01*
G01D02*
G02X178201Y517848I-495J495D01*
G01D02*
X177099D01*
G01X181054D02*
X178093Y514886D01*
G01D02*
G02X176032Y514033I-2060J2061D01*
G01D02*
X175679D01*
G01D02*
G03X174839Y513685I0J-1188D01*
G01D02*
X174558Y513404D01*
G01D02*
X174559D01*
G01D02*
X172333Y511178D01*
G01D02*
G02X164664Y508003I-7667J7669D01*
G01D02*
X159963D01*
G01D02*
G03X156403Y506529I-1J-5034D01*
G01D02*
X156060Y506185D01*
G01D02*
X154994Y505119D01*
G01D02*
Y505114D01*
G01X180845Y521961D02*
Y518057D01*
G01D02*
X181054Y517848D01*
G01X155877Y556670D02*
X156317Y557110D01*
G01D02*
Y607255D01*
G01D02*
X155877Y607695D01*
G01D02*
Y608895D01*
G01D02*
X156317Y609335D01*
G01D02*
Y610535D01*
G01D02*
X155877Y610975D01*
G01D02*
Y612175D01*
G01D02*
X156317Y612615D01*
G01D02*
Y613815D01*
G01D02*
X155877Y614255D01*
G01D02*
Y615455D01*
G01D02*
X156317Y615895D01*
G01D02*
Y617200D01*
G01D02*
X155877Y617640D01*
G01D02*
Y618840D01*
G01D02*
X156317Y619280D01*
G01D02*
Y620480D01*
G01D02*
X155877Y620920D01*
G01D02*
Y622120D01*
G01D02*
X156317Y622560D01*
G01D02*
Y672955D01*
G01D02*
X155877Y673395D01*
G01D02*
Y674595D01*
G01D02*
X156317Y675035D01*
G01D02*
Y676283D01*
G01D02*
X155877Y676723D01*
G01D02*
Y677875D01*
G01D02*
X156317Y678315D01*
G01D02*
Y679500D01*
G01D02*
X155877Y679940D01*
G01D02*
Y681140D01*
G01D02*
X156317Y681580D01*
G01D02*
Y682780D01*
G01D02*
X155877Y683220D01*
G01D02*
Y684420D01*
G01D02*
X156317Y684860D01*
G01D02*
Y716728D01*
G01X167316Y721897D02*
G02X174051Y738157I22997J-1D01*
G01D02*
X211253Y775359D01*
G01X168616Y721896D02*
G02X174971Y737238I21697J0D01*
G01D02*
X212172Y774439D01*
G01X156317Y716728D02*
X156318D01*
G01D02*
G02X165054Y737822I29831J2D01*
G01D02*
X166666Y739434D01*
G01D02*
Y740056D01*
G01D02*
X167515Y740905D01*
G01D02*
X168137D01*
G01D02*
X168986Y741753D01*
G01D02*
Y742376D01*
G01D02*
X169834Y743224D01*
G01D02*
X170456D01*
G01D02*
X171262Y744030D01*
G01D02*
Y744652D01*
G01D02*
X172111Y745501D01*
G01D02*
X172733D01*
G01D02*
X206538Y779306D01*
G01X157617Y716728D02*
G02X165974Y736902I28531J-1D01*
G01D02*
X166919Y737848D01*
G01D02*
X207458Y778386D01*
G01X153595Y735216D02*
X202536Y784157D01*
G01X154515Y734297D02*
X203456Y783238D01*
G01X159688Y829234D02*
G02X160400Y829529I712J-712D01*
G01D02*
X165238D01*
G01X159688Y832484D02*
G02X160159Y832679I471J-471D01*
G01D02*
X165238D01*
G01X159589Y817543D02*
Y817593D01*
G01D02*
G02X159940Y818440I1198J0D01*
G01D02*
X161286Y819786D01*
G01D02*
G02X161993Y820079I707J-706D01*
G01D02*
X165238D01*
G01X159137Y820712D02*
G02X165214Y823229I6077J-6077D01*
G01D02*
X165238D01*
G01X211253Y775359D02*
G03X218114Y791923I-16564J16564D01*
G01D02*
Y837430D01*
G01D02*
G03X215242Y844364I-9806J0D01*
G01X212172Y774439D02*
G03X219414Y791923I-17483J17483D01*
G01X206538Y779306D02*
G03X213470Y796041I-16735J16735D01*
G01D02*
Y831159D01*
G01D02*
G03X212006Y834694I-5000J0D01*
G01D02*
X206764Y839936D01*
G01X207458Y778386D02*
G03X214770Y796040I-17656J17654D01*
G01D02*
Y831159D01*
G01D02*
G03X212926Y835614I-6300J1D01*
G01D02*
X207684Y840856D01*
G01X202536Y784157D02*
X203289Y784911D01*
G01D02*
G03X207988Y796254I-11343J11344D01*
G01D02*
Y822767D01*
G01D02*
G03X205321Y829206I-9106J0D01*
G01D02*
X204649Y829878D01*
G01D02*
G03X199456Y832029I-5193J-5193D01*
G01D02*
X180756D01*
G01D02*
G03X179766Y831619I0J-1400D01*
G01D02*
G02X178523Y831104I-1243J1243D01*
G01D02*
X175118D01*
G01X203456Y783238D02*
X204209Y783992D01*
G01D02*
G03X209287Y796254I-12263J12261D01*
G01D02*
X209288D01*
G01D02*
Y822767D01*
G01D02*
G03X206240Y830126I-10406J1D01*
G01D02*
X205569Y830797D01*
G01D02*
G03X199456Y833329I-6113J-6112D01*
G01D02*
X180745D01*
G01D02*
G02X179774Y833731I0J1373D01*
G01D02*
G03X178511Y834254I-1263J-1263D01*
G01D02*
X175118D01*
G01X200136Y790083D02*
G03X202708Y796292I-6209J6209D01*
G01D02*
Y816053D01*
G01D02*
G03X201009Y820155I-5801J0D01*
G01D02*
X199680Y821484D01*
G01D02*
G03X197036Y822579I-2644J-2644D01*
G01D02*
X180869D01*
G01D02*
G03X179686Y822089I0J-1673D01*
G01D02*
G02X178636Y821654I-1050J1050D01*
G01D02*
X175118D01*
G01X201056Y789164D02*
G03X204008Y796291I-7129J7128D01*
G01D02*
Y816053D01*
G01D02*
G03X201928Y821075I-7101J1D01*
G01D02*
X200600Y822403D01*
G01D02*
G03X197036Y823879I-3563J-3563D01*
G01D02*
X180771D01*
G01D02*
G02X179755Y824300I0J1437D01*
G01D02*
G03X178538Y824804I-1217J-1217D01*
G01D02*
X175118D01*
G01X159426Y848357D02*
X159493Y848424D01*
G01D02*
X165238D01*
G01X159688Y851564D02*
X159698Y851574D01*
G01D02*
X165238D01*
G01Y838974D02*
X159431D01*
G01X159560Y842172D02*
X159562D01*
G01D02*
X159610Y842124D01*
G01D02*
X165238D01*
G01X215242Y844364D02*
X212858Y846748D01*
G01D02*
G03X202199Y851163I-10659J-10659D01*
G01D02*
X181125D01*
G01D02*
G03X179507Y850493I0J-2288D01*
G01D02*
G02X178314Y849999I-1193J1193D01*
G01D02*
X175118D01*
G01X219414Y837430D02*
G03X216161Y845284I-11106J1D01*
G01D02*
X213778Y847667D01*
G01D02*
G03X202199Y852463I-11578J-11578D01*
G01D02*
X180771D01*
G01D02*
G02X179943Y852806I0J1171D01*
G01D02*
G03X179115Y853149I-828J-828D01*
G01D02*
X175118D01*
G01X206764Y839936D02*
G03X203229Y841400I-3535J-3536D01*
G01D02*
X180902D01*
G01D02*
G03X179875Y840974I1J-1453D01*
G01D02*
X179874Y840973D01*
G01D02*
G02X178848Y840549I-1026J1029D01*
G01D02*
X175118D01*
G01X207684Y840856D02*
G03X203229Y842700I-4454J-4456D01*
G01D02*
X180806D01*
G01D02*
G02X179601Y843200I1J1705D01*
G01D02*
X179600Y843201D01*
G01D02*
G03X178396Y843699I-1204J-1206D01*
G01D02*
X175118D01*
G01X249415Y363969D02*
G03X252174Y362826I2759J2759D01*
G01D02*
X298960D01*
G01X249378Y360456D02*
X250200Y361279D01*
G01D02*
G02X250798Y361526I597J-598D01*
G01D02*
X513022D01*
G01X245105Y375055D02*
G03X247794Y373941I2689J2689D01*
G01D02*
X432771D01*
G01X245080Y371576D02*
X245614Y372110D01*
G01D02*
G02X246896Y372641I1282J-1282D01*
G01D02*
X248413D01*
G01D02*
G03X248417I2J814D01*
G01D02*
X432771D01*
G01X224885Y356264D02*
G03X223805Y353657I2607J-2607D01*
G01D02*
Y353400D01*
G01D02*
G03X224832Y350922I3503J0D01*
G01D02*
X224936Y350817D01*
G01D02*
G03X228554Y349575I3618J4648D01*
G01D02*
X295080D01*
G01X221424Y356317D02*
G02X222505Y353707I-2610J-2610D01*
G01D02*
Y353400D01*
G01D02*
G03X223910Y350004I4804J-1D01*
G01D02*
X224068Y349845D01*
G01D02*
G03X224529Y349506I4487J5619D01*
G01D02*
G03X228555Y348275I4023J5959D01*
G01D02*
X506120D01*
G01X241728Y364206D02*
X241003Y363481D01*
G01D02*
G02X239600Y362900I-1403J1403D01*
G01D02*
X238197D01*
G01D02*
G02X235300Y364100I0J4097D01*
G01D02*
X234604Y364795D01*
G01D02*
G02X233700Y366979I2184J2183D01*
G01D02*
G03X232200Y370600I-5121J0D01*
G01D02*
G03X225699Y373293I-6501J-6501D01*
G01X245915Y363969D02*
X241965D01*
G01D02*
X241728Y364206D01*
G01Y360206D02*
X241278Y360657D01*
G01D02*
G03X239000Y361600I-2277J-2278D01*
G01D02*
X238196D01*
G01D02*
G02X234381Y363180I1J5397D01*
G01D02*
X233684Y363875D01*
G01D02*
G02X232400Y366979I3105J3102D01*
G01D02*
G03X231280Y369680I-3820J-1D01*
G01D02*
G03X225698Y371993I-5583J-5580D01*
G01X245878Y360456D02*
X241978D01*
G01D02*
X241728Y360206D01*
G01X237455Y375305D02*
X236676Y374527D01*
G01D02*
G02X234821Y374148I-1214J1214D01*
G01D02*
G02X234398Y374380I760J1888D01*
G01D02*
G03X227837Y377057I-6560J-6698D01*
G01X241605Y375055D02*
X237705D01*
G01D02*
X237455Y375305D01*
G01Y371305D02*
X236683Y372076D01*
G01D02*
G03X235688Y372655I-1591J-1590D01*
G01D02*
G03X235091Y372736I-598J-2169D01*
G01D02*
G02X234664Y372828I488J3300D01*
G01D02*
G02X233548Y373392I920J3206D01*
G01D02*
G03X227838Y375757I-5710J-5710D01*
G01X241580Y371576D02*
X237726D01*
G01D02*
X237455Y371305D01*
G01X225089Y363907D02*
X224609Y364387D01*
G01D02*
G02X223875Y366159I1772J1772D01*
G01D02*
G03X223049Y367999I-2831J-166D01*
G01D02*
X222908Y368140D01*
G01D02*
G03X219400Y369593I-3508J-3508D01*
G01X224885Y359764D02*
Y363703D01*
G01D02*
X225089Y363907D01*
G01X221135Y363914D02*
X221249D01*
G01D02*
G03X221444Y363995I0J275D01*
G01D02*
X221924Y364475D01*
G01D02*
G03X222484Y365828I-1354J1353D01*
G01D02*
Y366525D01*
G01D02*
G03X222129Y367079I-1440J-532D01*
G01D02*
X221988Y367220D01*
G01D02*
G03X221889Y367315I-2583J-2593D01*
G01D02*
G03X219400Y368293I-2491J-2683D01*
G01X221424Y359817D02*
Y363625D01*
G01D02*
X221135Y363914D01*
G01X274012Y598747D02*
G02X281359Y601789I7345J-7348D01*
G01D02*
X759051D01*
G01X274932Y597827D02*
G02X281359Y600489I6427J-6427D01*
G01D02*
X759050D01*
G01X270112Y606144D02*
X270919Y606952D01*
G01D02*
G02X284253Y612477I13339J-13339D01*
G01D02*
X759100D01*
G01X271468Y605661D02*
X271839Y606033D01*
G01D02*
G02X284258Y611177I12419J-12419D01*
G01D02*
X770574D01*
G01X281442Y626486D02*
G02X284723Y627845I3281J-3281D01*
G01X280522Y627406D02*
G02X284723Y629145I4200J-4202D01*
G01D02*
X770728D01*
G01X284723Y627845D02*
X769754D01*
G01X286999Y640776D02*
G02X287235Y641003I5980J-5980D01*
G01D02*
G02X293477Y643447I6240J-6744D01*
G01X287900Y639837D02*
G02X293477Y642147I5577J-5577D01*
G01X219414Y791923D02*
Y837430D01*
G01X298960Y362826D02*
X299400Y363266D01*
G01D02*
X300600D01*
G01D02*
X301040Y362826D01*
G01D02*
X302240D01*
G01D02*
X302680Y363266D01*
G01D02*
X303880D01*
G01D02*
X304320Y362826D01*
G01D02*
X305520D01*
G01D02*
X305960Y363266D01*
G01D02*
X307160D01*
G01D02*
X307600Y362826D01*
G01D02*
X357600D01*
G01D02*
X358040Y363266D01*
G01D02*
X359240D01*
G01D02*
X359680Y362826D01*
G01D02*
X360880D01*
G01X295080Y349575D02*
X295520Y350015D01*
G01D02*
X296720D01*
G01D02*
X297160Y349575D01*
G01D02*
X298360D01*
G01D02*
X298800Y350015D01*
G01D02*
X300000D01*
G01D02*
X300440Y349575D01*
G01D02*
X301640D01*
G01D02*
X302080Y350015D01*
G01D02*
X303280D01*
G01D02*
X303720Y349575D01*
G01D02*
X304920D01*
G01D02*
X305360Y350015D01*
G01D02*
X306560D01*
G01D02*
X307000Y349575D01*
G01D02*
X308200D01*
G01D02*
X308640Y350015D01*
G01D02*
X309840D01*
G01D02*
X310280Y349575D01*
G01D02*
X360280D01*
G01X293477Y643447D02*
X294477D01*
G01D02*
X294877Y643847D01*
G01D02*
X295877D01*
G01D02*
X296277Y643447D01*
G01D02*
X297277D01*
G01D02*
X297677Y643847D01*
G01D02*
X298677D01*
G01D02*
X299077Y643447D01*
G01D02*
X769161D01*
G01X293477Y642147D02*
X771054D01*
G01X381560Y333200D02*
X382000Y333640D01*
G01D02*
X383200D01*
G01D02*
X383640Y333200D01*
G01D02*
X384840D01*
G01D02*
X385280Y333640D01*
G01D02*
X386480D01*
G01D02*
X386920Y333200D01*
G01D02*
X436920D01*
G01X430060Y341400D02*
X430500Y341840D01*
G01X360880Y362826D02*
X361320Y363266D01*
G01D02*
X362520D01*
G01D02*
X362960Y362826D01*
G01D02*
X364160D01*
G01D02*
X364600Y363266D01*
G01D02*
X365800D01*
G01D02*
X366240Y362826D01*
G01D02*
X367440D01*
G01D02*
X367880Y363266D01*
G01D02*
X369080D01*
G01D02*
X369520Y362826D01*
G01D02*
X370720D01*
G01D02*
X371160Y363266D01*
G01D02*
X372360D01*
G01D02*
X372800Y362826D01*
G01D02*
X422800D01*
G01D02*
X423240Y363266D01*
G01D02*
X424440D01*
G01D02*
X424880Y362826D01*
G01D02*
X426080D01*
G01D02*
X426520Y363266D01*
G01D02*
X427720D01*
G01D02*
X428160Y362826D01*
G01D02*
X429360D01*
G01D02*
X429800Y363266D01*
G01D02*
X431000D01*
G01X360280Y349575D02*
X360720Y350015D01*
G01D02*
X361920D01*
G01D02*
X362360Y349575D01*
G01D02*
X363560D01*
G01D02*
X364000Y350015D01*
G01D02*
X365200D01*
G01D02*
X365640Y349575D01*
G01D02*
X366840D01*
G01D02*
X367280Y350015D01*
G01D02*
X368480D01*
G01D02*
X368920Y349575D01*
G01D02*
X370120D01*
G01D02*
X370560Y350015D01*
G01D02*
X371760D01*
G01D02*
X372200Y349575D01*
G01D02*
X373400D01*
G01D02*
X373840Y350015D01*
G01D02*
X375040D01*
G01D02*
X375480Y349575D01*
G01D02*
X425480D01*
G01D02*
X425920Y350015D01*
G01D02*
X427120D01*
G01D02*
X427560Y349575D01*
G01D02*
X428760D01*
G01D02*
X429200Y350015D01*
G01D02*
X430400D01*
G01X461600Y316017D02*
X462040Y316457D01*
G01D02*
X463240D01*
G01D02*
X463680Y316017D01*
G01D02*
X464880D01*
G01D02*
X465320Y316457D01*
G01D02*
X466520D01*
G01D02*
X466960Y316017D01*
G01D02*
X468160D01*
G01D02*
X468600Y316457D01*
G01D02*
X469800D01*
G01D02*
X470240Y316017D01*
G01D02*
X520240D01*
G01X500540Y328800D02*
X500980Y329240D01*
G01X436920Y333200D02*
X437360Y333640D01*
G01D02*
X438560D01*
G01D02*
X439000Y333200D01*
G01D02*
X440200D01*
G01D02*
X440640Y333640D01*
G01D02*
X441840D01*
G01D02*
X442280Y333200D01*
G01D02*
X443480D01*
G01D02*
X443920Y333640D01*
G01D02*
X445120D01*
G01D02*
X445560Y333200D01*
G01D02*
X446760D01*
G01D02*
X447200Y333640D01*
G01D02*
X448400D01*
G01D02*
X448840Y333200D01*
G01D02*
X498840D01*
G01D02*
X499280Y333640D01*
G01D02*
X500480D01*
G01D02*
X500920Y333200D01*
G01X430500Y341840D02*
X431700D01*
G01D02*
X432140Y341400D01*
G01D02*
X433340D01*
G01D02*
X433780Y341840D01*
G01D02*
X434980D01*
G01D02*
X435420Y341400D01*
G01D02*
X436620D01*
G01D02*
X437060Y341840D01*
G01D02*
X438260D01*
G01D02*
X438700Y341400D01*
G01D02*
X439900D01*
G01D02*
X440340Y341840D01*
G01D02*
X441540D01*
G01D02*
X441980Y341400D01*
G01D02*
X491980D01*
G01D02*
X492420Y341840D01*
G01D02*
X493620D01*
G01D02*
X494060Y341400D01*
G01D02*
X495260D01*
G01D02*
X495700Y341840D01*
G01D02*
X496900D01*
G01D02*
X497340Y341400D01*
G01D02*
X498540D01*
G01D02*
X498980Y341840D01*
G01D02*
X500180D01*
G01D02*
X500620Y341400D01*
G01X431000Y363266D02*
X431440Y362826D01*
G01D02*
X432640D01*
G01D02*
X433080Y363266D01*
G01D02*
X434280D01*
G01D02*
X434720Y362826D01*
G01D02*
X435920D01*
G01D02*
X436360Y363266D01*
G01D02*
X437560D01*
G01D02*
X438000Y362826D01*
G01D02*
X488000D01*
G01D02*
X488440Y363266D01*
G01D02*
X489640D01*
G01D02*
X490080Y362826D01*
G01D02*
X491280D01*
G01D02*
X491720Y363266D01*
G01D02*
X492920D01*
G01D02*
X493360Y362826D01*
G01D02*
X494560D01*
G01D02*
X495000Y363266D01*
G01D02*
X496200D01*
G01D02*
X496640Y362826D01*
G01D02*
X497840D01*
G01D02*
X498280Y363266D01*
G01D02*
X499480D01*
G01D02*
X499920Y362826D01*
G01D02*
X501120D01*
G01X432771Y373941D02*
G03X435033Y374879I-1J3200D01*
G01D02*
X571114Y510960D01*
G01X432771Y372641D02*
G03X435953Y373959I0J4500D01*
G01D02*
X640723Y578729D01*
G01X430400Y350015D02*
X430840Y349575D01*
G01D02*
X432040D01*
G01D02*
X432480Y350015D01*
G01D02*
X433680D01*
G01D02*
X434120Y349575D01*
G01D02*
X435320D01*
G01D02*
X435760Y350015D01*
G01D02*
X436960D01*
G01D02*
X437400Y349575D01*
G01D02*
X438600D01*
G01D02*
X439040Y350015D01*
G01D02*
X440240D01*
G01D02*
X440680Y349575D01*
G01D02*
X490680D01*
G01D02*
X491120Y350015D01*
G01D02*
X492320D01*
G01D02*
X492760Y349575D01*
G01D02*
X493960D01*
G01D02*
X494400Y350015D01*
G01D02*
X495600D01*
G01D02*
X496040Y349575D01*
G01D02*
X497240D01*
G01D02*
X497680Y350015D01*
G01D02*
X498880D01*
G01D02*
X499320Y349575D01*
G01D02*
X500520D01*
G01D02*
X500960Y350015D01*
G01X516485Y306902D02*
X516925Y307342D01*
G01D02*
X518125D01*
G01D02*
X518565Y306902D01*
G01D02*
X519765D01*
G01D02*
X520205Y307342D01*
G01D02*
X521405D01*
G01D02*
X521845Y306902D01*
G01D02*
X523045D01*
G01D02*
X523485Y307342D01*
G01D02*
X524685D01*
G01D02*
X525125Y306902D01*
G01D02*
X526325D01*
G01D02*
X526765Y307342D01*
G01D02*
X527965D01*
G01D02*
X528405Y306902D01*
G01D02*
X578405D01*
G01X518665Y311381D02*
X519105Y311821D01*
G01D02*
X520305D01*
G01D02*
X520745Y311381D01*
G01D02*
X521945D01*
G01D02*
X522385Y311821D01*
G01D02*
X523585D01*
G01D02*
X524025Y311381D01*
G01D02*
X525225D01*
G01D02*
X525665Y311821D01*
G01D02*
X526865D01*
G01D02*
X527305Y311381D01*
G01D02*
X528505D01*
G01D02*
X528945Y311821D01*
G01D02*
X530145D01*
G01D02*
X530585Y311381D01*
G01D02*
X580585D01*
G01X520240Y316017D02*
X520680Y316457D01*
G01D02*
X521880D01*
G01D02*
X522320Y316017D01*
G01D02*
X523520D01*
G01D02*
X523960Y316457D01*
G01D02*
X525160D01*
G01D02*
X525600Y316017D01*
G01D02*
X526800D01*
G01D02*
X527240Y316457D01*
G01D02*
X528440D01*
G01D02*
X528880Y316017D01*
G01D02*
X530080D01*
G01D02*
X530520Y316457D01*
G01D02*
X531720D01*
G01D02*
X532160Y316017D01*
G01D02*
X582160D01*
G01X510940Y320157D02*
X511380Y320597D01*
G01D02*
X512580D01*
G01D02*
X513020Y320157D01*
G01D02*
X514220D01*
G01D02*
X514660Y320597D01*
G01D02*
X515860D01*
G01D02*
X516300Y320157D01*
G01D02*
X566300D01*
G01D02*
X566740Y320597D01*
G01D02*
X567940D01*
G01D02*
X568380Y320157D01*
G01D02*
X569580D01*
G01D02*
X570020Y320597D01*
G01D02*
X571220D01*
G01X509176Y324580D02*
X509616Y325020D01*
G01D02*
X510816D01*
G01D02*
X511256Y324580D01*
G01D02*
X512456D01*
G01D02*
X512896Y325020D01*
G01D02*
X514096D01*
G01D02*
X514536Y324580D01*
G01D02*
X515736D01*
G01D02*
X516176Y325020D01*
G01D02*
X517376D01*
G01D02*
X517816Y324580D01*
G01D02*
X519016D01*
G01D02*
X519456Y325020D01*
G01D02*
X520656D01*
G01D02*
X521096Y324580D01*
G01D02*
X571096D01*
G01X500980Y329240D02*
X502180D01*
G01D02*
X502620Y328800D01*
G01D02*
X503820D01*
G01D02*
X504260Y329240D01*
G01D02*
X505460D01*
G01D02*
X505900Y328800D01*
G01D02*
X555900D01*
G01D02*
X556340Y329240D01*
G01D02*
X557540D01*
G01D02*
X557980Y328800D01*
G01D02*
X559180D01*
G01D02*
X559620Y329240D01*
G01D02*
X560820D01*
G01D02*
X561260Y328800D01*
G01D02*
X562460D01*
G01D02*
X562900Y329240D01*
G01D02*
X564100D01*
G01D02*
X564540Y328800D01*
G01D02*
X565740D01*
G01D02*
X566180Y329240D01*
G01D02*
X567380D01*
G01D02*
X567820Y328800D01*
G01D02*
X569020D01*
G01D02*
X569460Y329240D01*
G01D02*
X570660D01*
G01D02*
X571100Y328800D01*
G01X500920Y333200D02*
X502120D01*
G01D02*
X502560Y333640D01*
G01D02*
X503760D01*
G01D02*
X504200Y333200D01*
G01D02*
X505400D01*
G01D02*
X505840Y333640D01*
G01D02*
X507040D01*
G01D02*
X507480Y333200D01*
G01D02*
X508680D01*
G01D02*
X509120Y333640D01*
G01D02*
X510320D01*
G01D02*
X510760Y333200D01*
G01D02*
X560760D01*
G01D02*
X561200Y333640D01*
G01D02*
X562400D01*
G01D02*
X562840Y333200D01*
G01D02*
X564040D01*
G01D02*
X564480Y333640D01*
G01D02*
X565680D01*
G01D02*
X566120Y333200D01*
G01D02*
X567320D01*
G01D02*
X567760Y333640D01*
G01D02*
X568960D01*
G01D02*
X569400Y333200D01*
G01D02*
X570600D01*
G01D02*
X571040Y333640D01*
G01X550044Y337520D02*
G03X551812Y338252I0J2501D01*
G01D02*
X663062Y449502D01*
G01X550044Y336220D02*
G03X552732Y337332I1J3802D01*
G01D02*
X663982Y448582D01*
G01X500620Y341400D02*
X501820D01*
G01D02*
X502260Y341840D01*
G01D02*
X503460D01*
G01D02*
X503900Y341400D01*
G01D02*
X508000D01*
G01D02*
G03X528314Y346072I0J46499D01*
G01X508002Y340100D02*
G03X528882Y344902I0J47796D01*
G01D02*
G03X541799Y354099I-20881J42996D01*
G01X501120Y362826D02*
X501560Y363266D01*
G01D02*
X502760D01*
G01D02*
X503200Y362826D01*
G01D02*
X513022D01*
G01D02*
G03X515284Y363764I-1J3200D01*
G01D02*
X649934Y498414D01*
G01X513022Y361526D02*
G03X516204Y362844I0J4500D01*
G01D02*
X650854Y497494D01*
G01X500960Y350015D02*
X502160D01*
G01D02*
X502600Y349575D01*
G01D02*
X506120D01*
G01D02*
G03X509302Y350893I0J4500D01*
G01D02*
X648521Y490112D01*
G01X506120Y348275D02*
G03X510222Y349973I1J5801D01*
G01D02*
X649441Y489192D01*
G01X528314Y346072D02*
G03X540879Y355019I-20314J41826D01*
G01D02*
X651800Y465940D01*
G01X541799Y354099D02*
X652300Y464600D01*
G01X578405Y306902D02*
X578845Y307342D01*
G01D02*
X580045D01*
G01D02*
X580485Y306902D01*
G01D02*
X581685D01*
G01D02*
X582125Y307342D01*
G01D02*
X583325D01*
G01D02*
X583765Y306902D01*
G01D02*
X584965D01*
G01D02*
X585405Y307342D01*
G01D02*
X586605D01*
G01D02*
X587045Y306902D01*
G01D02*
X588245D01*
G01D02*
X588685Y307342D01*
G01D02*
X589885D01*
G01D02*
X590325Y306902D01*
G01D02*
X591525D01*
G01D02*
X591965Y307342D01*
G01D02*
X593165D01*
G01D02*
X593605Y306902D01*
G01D02*
X634531D01*
G01D02*
G03X638066Y308366I0J5000D01*
G01D02*
X644287Y314587D01*
G01X674316Y342776D02*
X638986Y307446D01*
G01D02*
G02X634531Y305602I-4454J4456D01*
G01X580585Y311381D02*
X581025Y311821D01*
G01D02*
X582225D01*
G01D02*
X582665Y311381D01*
G01D02*
X583865D01*
G01D02*
X584305Y311821D01*
G01D02*
X585505D01*
G01D02*
X585945Y311381D01*
G01D02*
X587145D01*
G01D02*
X587585Y311821D01*
G01D02*
X588785D01*
G01D02*
X589225Y311381D01*
G01D02*
X590425D01*
G01D02*
X590865Y311821D01*
G01D02*
X592065D01*
G01D02*
X592505Y311381D01*
G01D02*
X629910D01*
G01D02*
G03X633445Y312845I0J5000D01*
G01D02*
X644029Y323429D01*
G01X680977Y358537D02*
X634365Y311925D01*
G01D02*
G02X629910Y310081I-4454J4456D01*
G01X582160Y316017D02*
X582600Y316457D01*
G01D02*
X583800D01*
G01D02*
X584240Y316017D01*
G01D02*
X585440D01*
G01D02*
X585880Y316457D01*
G01D02*
X587080D01*
G01D02*
X587520Y316017D01*
G01D02*
X588720D01*
G01D02*
X589160Y316457D01*
G01D02*
X590360D01*
G01D02*
X590800Y316017D01*
G01D02*
X592000D01*
G01D02*
X592440Y316457D01*
G01D02*
X593640D01*
G01D02*
X594080Y316017D01*
G01D02*
X625446D01*
G01D02*
G03X628981Y317481I0J5000D01*
G01D02*
X641105Y329605D01*
G01D02*
Y330227D01*
G01D02*
X641953Y331076D01*
G01X625446Y314717D02*
G03X629901Y316561I1J6300D01*
G01D02*
X695510Y382170D01*
G01X571220Y320597D02*
X571660Y320157D01*
G01D02*
X572860D01*
G01D02*
X573300Y320597D01*
G01D02*
X574500D01*
G01D02*
X574940Y320157D01*
G01D02*
X576140D01*
G01D02*
X576580Y320597D01*
G01D02*
X577780D01*
G01D02*
X578220Y320157D01*
G01D02*
X579420D01*
G01D02*
X579860Y320597D01*
G01D02*
X581060D01*
G01D02*
X581500Y320157D01*
G01D02*
X621100D01*
G01D02*
G03X623928Y321329I-1J4000D01*
G01D02*
X623929D01*
G01D02*
X630207Y327607D01*
G01D02*
Y328230D01*
G01D02*
X631056Y329078D01*
G01D02*
X631678D01*
G01D02*
X632526Y329927D01*
G01D02*
Y330549D01*
G01D02*
X633375Y331397D01*
G01D02*
X633997D01*
G01D02*
X634846Y332246D01*
G01D02*
Y332868D01*
G01D02*
X635694Y333717D01*
G01D02*
X636317D01*
G01D02*
X637165Y334565D01*
G01D02*
Y335187D01*
G01D02*
X638014Y336036D01*
G01D02*
X638636D01*
G01D02*
X639484Y336884D01*
G01D02*
Y337507D01*
G01D02*
X640333Y338355D01*
G01D02*
X640955D01*
G01D02*
X677310Y374710D01*
G01X701069Y396630D02*
X624849Y320410D01*
G01D02*
G02X621100Y318857I-3749J3749D01*
G01X571096Y324580D02*
X571536Y325020D01*
G01D02*
X572736D01*
G01D02*
X573176Y324580D01*
G01D02*
X574376D01*
G01D02*
X574816Y325020D01*
G01D02*
X576016D01*
G01D02*
X576456Y324580D01*
G01D02*
X577656D01*
G01D02*
X578096Y325020D01*
G01D02*
X579296D01*
G01D02*
X579736Y324580D01*
G01D02*
X580936D01*
G01D02*
X581376Y325020D01*
G01D02*
X582576D01*
G01D02*
X583016Y324580D01*
G01D02*
X618700D01*
G01D02*
G03X621217Y325622I1J3559D01*
G01D02*
Y325623D01*
G01D02*
X632009Y336415D01*
G01D02*
Y337038D01*
G01D02*
X632858Y337886D01*
G01D02*
X633480D01*
G01D02*
X634329Y338735D01*
G01D02*
Y339357D01*
G01D02*
X635177Y340206D01*
G01D02*
X635800D01*
G01D02*
X636648Y341054D01*
G01D02*
Y341676D01*
G01D02*
X637497Y342525D01*
G01D02*
X638119D01*
G01D02*
X638967Y343373D01*
G01D02*
Y343996D01*
G01D02*
X639816Y344844D01*
G01D02*
X640438D01*
G01D02*
X678558Y382964D01*
G01X618700Y323280D02*
G03X622137Y324703I1J4860D01*
G01D02*
Y324704D01*
G01D02*
X710616Y413183D01*
G01X571100Y328800D02*
X614500D01*
G01D02*
G03X616772Y329741I0J3213D01*
G01D02*
X620276Y333245D01*
G01D02*
Y333867D01*
G01D02*
X621125Y334716D01*
G01D02*
X621747D01*
G01D02*
X622595Y335564D01*
G01D02*
Y336187D01*
G01D02*
X623444Y337035D01*
G01D02*
X624066D01*
G01D02*
X624915Y337884D01*
G01D02*
Y338506D01*
G01D02*
X625763Y339354D01*
G01D02*
X626385D01*
G01D02*
X627234Y340203D01*
G01D02*
Y340825D01*
G01D02*
X628082Y341674D01*
G01D02*
X628705D01*
G01D02*
X629553Y342522D01*
G01D02*
Y343145D01*
G01D02*
X630402Y343993D01*
G01D02*
X631024D01*
G01D02*
X667354Y380323D01*
G01X614500Y327500D02*
G03X617694Y328823I0J4517D01*
G01D02*
X718135Y429264D01*
G01X571040Y333640D02*
X572240D01*
G01D02*
X572680Y333200D01*
G01D02*
X611000D01*
G01D02*
G03X612878Y333978I0J2656D01*
G01D02*
X620905Y342005D01*
G01D02*
Y342628D01*
G01D02*
X621753Y343476D01*
G01D02*
X622376D01*
G01D02*
X623224Y344325D01*
G01D02*
Y344947D01*
G01D02*
X624073Y345795D01*
G01X611000Y331900D02*
G03X613798Y333059I0J3957D01*
G01D02*
X717919Y437180D01*
G01X624073Y345795D02*
X624695D01*
G01D02*
X625544Y346644D01*
G01D02*
Y347266D01*
G01D02*
X626392Y348115D01*
G01D02*
X627014D01*
G01D02*
X627863Y348963D01*
G01D02*
Y349585D01*
G01D02*
X628711Y350434D01*
G01D02*
X629334D01*
G01D02*
X716750Y437850D01*
G01X571114Y510960D02*
Y511582D01*
G01D02*
X571963Y512431D01*
G01D02*
X572585D01*
G01D02*
X573434Y513280D01*
G01D02*
Y513902D01*
G01D02*
X574282Y514750D01*
G01D02*
X574904D01*
G01D02*
X575753Y515599D01*
G01D02*
Y516221D01*
G01D02*
X576601Y517070D01*
G01D02*
X577224D01*
G01D02*
X612579Y552425D01*
G01D02*
Y553047D01*
G01D02*
X613428Y553896D01*
G01D02*
X614050D01*
G01D02*
X614898Y554744D01*
G01D02*
Y555367D01*
G01D02*
X615747Y556215D01*
G01D02*
X616369D01*
G01D02*
X617218Y557064D01*
G01D02*
Y557686D01*
G01D02*
X618066Y558534D01*
G01D02*
X618688D01*
G01D02*
X619537Y559383D01*
G01D02*
Y560005D01*
G01D02*
X620385Y560854D01*
G01D02*
X621008D01*
G01D02*
X621856Y561702D01*
G01D02*
Y562324D01*
G01D02*
X622705Y563173D01*
G01D02*
X623327D01*
G01D02*
X639803Y579649D01*
G01D02*
G02X643905Y581347I4101J-4103D01*
G01X640723Y578729D02*
G02X643905Y580047I3182J-3182D01*
G01X644287Y314587D02*
Y315209D01*
G01D02*
X645136Y316058D01*
G01D02*
X645758D01*
G01D02*
X646607Y316906D01*
G01D02*
Y317529D01*
G01D02*
X647455Y318377D01*
G01D02*
X648077D01*
G01D02*
X648926Y319226D01*
G01D02*
Y319848D01*
G01D02*
X649774Y320696D01*
G01D02*
X650397D01*
G01D02*
X651245Y321545D01*
G01D02*
Y322167D01*
G01D02*
X652094Y323016D01*
G01D02*
X652716D01*
G01D02*
X673396Y343696D01*
G01D02*
G02X676931Y345160I3535J-3536D01*
G01D02*
X696660D01*
G01D02*
X697100Y345600D01*
G01X698339D02*
X698779Y345160D01*
G01D02*
X700379D01*
G01D02*
X700819Y345600D01*
G01X702419D02*
X702859Y345160D01*
G01D02*
X704459D01*
G01D02*
X704899Y345600D01*
G01X706499D02*
X706939Y345160D01*
G01D02*
X708539D01*
G01D02*
X708979Y345600D01*
G01X710579D02*
X711019Y345160D01*
G01D02*
X712619D01*
G01X769907Y343860D02*
X676931D01*
G01D02*
G03X674316Y342776I1J-3699D01*
G01X644029Y323429D02*
Y324051D01*
G01D02*
X644877Y324899D01*
G01D02*
X645500D01*
G01D02*
X646348Y325748D01*
G01D02*
Y326370D01*
G01D02*
X647197Y327219D01*
G01D02*
X647819D01*
G01D02*
X648667Y328067D01*
G01D02*
Y328690D01*
G01D02*
X649516Y329538D01*
G01D02*
X650138D01*
G01D02*
X650987Y330387D01*
G01D02*
Y331009D01*
G01D02*
X651835Y331857D01*
G01D02*
X652458D01*
G01D02*
X653306Y332706D01*
G01D02*
Y333328D01*
G01D02*
X654155Y334177D01*
G01D02*
X654777D01*
G01D02*
X680057Y359457D01*
G01X641953Y331076D02*
X642576D01*
G01D02*
X643424Y331924D01*
G01D02*
Y332546D01*
G01D02*
X644273Y333395D01*
G01D02*
X644895D01*
G01D02*
X645744Y334244D01*
G01D02*
Y334866D01*
G01D02*
X646592Y335714D01*
G01D02*
X647214D01*
G01D02*
X648063Y336563D01*
G01D02*
Y337185D01*
G01D02*
X648911Y338034D01*
G01D02*
X649534D01*
G01D02*
X694590Y383090D01*
G01X697100Y345600D02*
X698339D01*
G01X700819D02*
X702419D01*
G01X704899D02*
X706499D01*
G01X708979D02*
X710579D01*
G01X680057Y359457D02*
G02X683592Y360921I3535J-3536D01*
G01D02*
X695980D01*
G01D02*
X696420Y361361D01*
G01D02*
X697620D01*
G01D02*
X698060Y360921D01*
G01D02*
X699260D01*
G01D02*
X699700Y361361D01*
G01D02*
X700900D01*
G01D02*
X701340Y360921D01*
G01D02*
X702540D01*
G01D02*
X702980Y361361D01*
G01D02*
X704180D01*
G01D02*
X704620Y360921D01*
G01D02*
X705820D01*
G01D02*
X706260Y361361D01*
G01D02*
X707460D01*
G01D02*
X707900Y360921D01*
G01D02*
X709021D01*
G01D02*
X709400Y361300D01*
G01D02*
X710521D01*
G01D02*
X710900Y360921D01*
G01D02*
X769899D01*
G01X770039Y359621D02*
X683592D01*
G01D02*
G03X680977Y358537I1J-3699D01*
G01X694590Y383090D02*
G02X698125Y384554I3535J-3536D01*
G01D02*
X700700D01*
G01D02*
X701679Y384555D01*
G01D02*
X702119Y384994D01*
G01D02*
X703320D01*
G01D02*
X703760Y384555D01*
G01D02*
X704960Y384554D01*
G01D02*
X705399Y384994D01*
G01D02*
X706599D01*
G01D02*
X707040Y384554D01*
G01D02*
X708239D01*
G01D02*
X708680Y384994D01*
G01D02*
X709880D01*
G01D02*
X710319Y384554D01*
G01D02*
X711519Y384555D01*
G01D02*
X711959Y384994D01*
G01X695510Y382170D02*
G02X698125Y383254I2616J-2615D01*
G01D02*
X769796D01*
G01X677310Y374710D02*
Y375332D01*
G01D02*
X678159Y376181D01*
G01D02*
X678781D01*
G01D02*
X679630Y377029D01*
G01D02*
Y377652D01*
G01D02*
X680478Y378500D01*
G01D02*
X681100D01*
G01D02*
X681949Y379349D01*
G01D02*
Y379971D01*
G01D02*
X682797Y380819D01*
G01D02*
X683420D01*
G01D02*
X684268Y381668D01*
G01D02*
Y382290D01*
G01D02*
X685117Y383139D01*
G01D02*
X685739D01*
G01D02*
X686500Y383900D01*
G01D02*
Y384700D01*
G01D02*
X687250Y385450D01*
G01D02*
X688050D01*
G01D02*
X701517Y398917D01*
G01D02*
G02X704800Y400277I3283J-3283D01*
G01D02*
X769945D01*
G01X769892Y398977D02*
X704800D01*
G01D02*
G03X702438Y397998I1J-3341D01*
G01D02*
X701069Y396630D01*
G01X678558Y382964D02*
Y383586D01*
G01D02*
X679406Y384435D01*
G01D02*
X680029D01*
G01D02*
X680877Y385283D01*
G01D02*
Y385906D01*
G01D02*
X681726Y386754D01*
G01D02*
X682348D01*
G01D02*
X683197Y387603D01*
G01D02*
Y388225D01*
G01D02*
X684045Y389074D01*
G01D02*
X684667D01*
G01D02*
X685516Y389922D01*
G01D02*
Y390544D01*
G01D02*
X686364Y391393D01*
G01D02*
X686987D01*
G01D02*
X687835Y392241D01*
G01D02*
Y392864D01*
G01D02*
X688684Y393712D01*
G01D02*
X689306D01*
G01D02*
X710431Y414837D01*
G01D02*
G02X713299Y416025I2869J-2869D01*
G01X710616Y413183D02*
X711351Y413917D01*
G01D02*
G02X713300Y414725I1950J-1949D01*
G01X667354Y380323D02*
Y380945D01*
G01D02*
X668203Y381794D01*
G01D02*
X668825D01*
G01D02*
X669674Y382642D01*
G01D02*
Y383264D01*
G01D02*
X670522Y384113D01*
G01D02*
X671144D01*
G01D02*
X671993Y384961D01*
G01D02*
Y385584D01*
G01D02*
X672842Y386432D01*
G01D02*
X673464D01*
G01D02*
X674312Y387281D01*
G01D02*
Y387903D01*
G01D02*
X675161Y388752D01*
G01D02*
X675783D01*
G01D02*
X676565Y389534D01*
G01D02*
Y390365D01*
G01D02*
X677200Y391000D01*
G01D02*
X678031D01*
G01D02*
X716065Y429034D01*
G01X711459Y453923D02*
G03X711650Y453462I652J0D01*
G01D02*
X713778Y451334D01*
G01X665909Y466173D02*
X667362Y464720D01*
G01D02*
G02X667903Y463414I-1306J-1306D01*
G01D02*
Y462258D01*
G01D02*
G02X667486Y461251I-1424J0D01*
G01D02*
X666211Y459976D01*
G01D02*
G02X665103Y459517I-1108J1108D01*
G01D02*
X663141D01*
G01D02*
G02X661760Y460089I0J1953D01*
G01X669959Y462023D02*
Y461885D01*
G01D02*
X667245Y459171D01*
G01D02*
G02X664942Y458217I-2303J2303D01*
G01D02*
X664303D01*
G01D02*
G03X662880Y457627I1J-2013D01*
G01D02*
X662166Y456914D01*
G01X649359Y482723D02*
X650852Y481229D01*
G01D02*
G02X651304Y480138I-1091J-1091D01*
G01D02*
Y478614D01*
G01D02*
G02X650833Y477477I-1608J0D01*
G01D02*
X649294Y475938D01*
G01D02*
G02X647536Y475210I-1758J1758D01*
G01D02*
X647396D01*
G01D02*
G02X646456Y475751I534J2014D01*
G01D02*
X646246Y475961D01*
G01X653459Y478423D02*
Y478263D01*
G01D02*
X651564Y476368D01*
G01D02*
X651563D01*
G01D02*
X650623Y475428D01*
G01D02*
Y475427D01*
G01D02*
X650214Y475018D01*
G01D02*
G02X648545Y474046I-2677J2678D01*
G01D02*
G03X647733Y473573I490J-1775D01*
G01D02*
X646794Y472634D01*
G01X663062Y449502D02*
G02X667164Y451200I4101J-4103D01*
G01D02*
X672765D01*
G01D02*
G03X675027Y452138I-1J3200D01*
G01D02*
X675858Y452969D01*
G01D02*
G03X676057Y453207I-1192J1198D01*
G01D02*
X676056D01*
G01D02*
G03X676353Y454164I-1393J957D01*
G01D02*
Y455138D01*
G01D02*
G03X675935Y456147I-1427J0D01*
G01D02*
X674109Y457973D01*
G01X663982Y448582D02*
G02X667164Y449900I3182J-3182D01*
G01D02*
X672765D01*
G01D02*
G03X675947Y451218I0J4500D01*
G01D02*
X676778Y452049D01*
G01D02*
G03X677129Y452471I-2114J2115D01*
G01D02*
X677748Y453373D01*
G01D02*
G02X678509Y453773I761J-523D01*
G01X651800Y465940D02*
G02X652187Y466301I5398J-5399D01*
G01D02*
G02X657004Y468553I5512J-5512D01*
G01D02*
X657606D01*
G01D02*
G03X659306Y469257I0J2404D01*
G01D02*
G03X659703Y470214I-957J958D01*
G01D02*
Y471400D01*
G01D02*
G03X659081Y472900I-2122J-1D01*
G01D02*
X657609Y474373D01*
G01X652300Y464600D02*
X652720Y465021D01*
G01D02*
G02X652955Y465243I3889J-3881D01*
G01D02*
X653041Y465319D01*
G01D02*
G02X653075Y465349I4207J-4734D01*
G01D02*
G02X657120Y467258I4625J-4560D01*
G01D02*
X657620D01*
G01D02*
G03X660225Y468337I0J3684D01*
G01D02*
X661389Y469501D01*
G01D02*
G03X661709Y470273I-771J772D01*
G01X652859Y482723D02*
X652959Y482823D01*
G01D02*
X736859D01*
G01X732574Y481523D02*
X657232D01*
G01D02*
G03X656003Y481014I0J-1738D01*
G01D02*
G03Y479379I818J-818D01*
G01D02*
X656959Y478423D01*
G01X712059Y458023D02*
X677659D01*
G01D02*
X677559Y457923D01*
G01X707959Y453923D02*
X708883Y454848D01*
G01D02*
G03X709203Y455619I-771J772D01*
G01D02*
G03X708853Y456464I-1195J0D01*
G01D02*
G03X708228Y456723I-625J-625D01*
G01D02*
X681603D01*
G01D02*
G03X680993Y456471I-1J-862D01*
G01D02*
X680805Y456282D01*
G01D02*
G03X680617Y455828I454J-454D01*
G01D02*
Y455391D01*
G01D02*
G03X680848Y454835I787J1D01*
G01D02*
X681959Y453723D01*
G01X661059Y474323D02*
X728459D01*
G01X724657Y473023D02*
X664990D01*
G01D02*
G03X664003Y472614I0J-1396D01*
G01D02*
G03Y471379I618J-617D01*
G01D02*
X665159Y470223D01*
G01X665909Y462673D02*
X664079D01*
G01D02*
G02X662604Y463284I0J2086D01*
G01X670009Y458573D02*
G02X669853Y458198I-531J1D01*
G01D02*
X667745Y456089D01*
G01X646251Y479161D02*
X649297D01*
G01D02*
X649409Y479273D01*
G01X650837Y472421D02*
G02X651164Y473212I1118J1D01*
G01D02*
X651501Y473548D01*
G01D02*
X652601Y474648D01*
G01D02*
G02X653386Y474973I785J-785D01*
G01D02*
X653509D01*
G01X674109Y454473D02*
X671270D01*
G01D02*
X671145Y454348D01*
G01X678509Y450273D02*
X677829D01*
G01D02*
X675745Y448189D01*
G01X653351Y470098D02*
X653578Y470326D01*
G01D02*
G02X654900Y470873I1321J-1322D01*
G01D02*
X657609D01*
G01X661709Y466773D02*
G03X659856Y466006I0J-2622D01*
G01D02*
G03X659855Y466005I1853J-1854D01*
G01D02*
X658195Y464344D01*
G01D02*
Y464248D01*
G01X711409Y450473D02*
G02X712806Y449895I1J-1975D01*
G01X719584Y465802D02*
X670134D01*
G01D02*
G02X669359Y466123I0J1096D01*
G01X673459Y462023D02*
X672824Y462659D01*
G01D02*
G02X672311Y463896I1237J1238D01*
G01D02*
G02X672643Y464397I1401J-568D01*
G01D02*
G02X673171Y464502I527J-1268D01*
G01D02*
X716477D01*
G01X649934Y498414D02*
G02X654036Y500112I4101J-4103D01*
G01D02*
X711321D01*
G01D02*
G03X714502Y501430I-1J4500D01*
G01X650854Y497494D02*
G02X654036Y498812I3182J-3182D01*
G01D02*
X711320D01*
G01D02*
G03X715422Y500510I1J5801D01*
G01X648521Y490112D02*
G02X651703Y491430I3182J-3182D01*
G01D02*
X725611D01*
G01X649441Y489192D02*
G02X651703Y490130I2263J-2262D01*
G01D02*
X725611D01*
G01X643905Y581347D02*
X685200D01*
G01D02*
X685640Y581787D01*
G01D02*
X686840D01*
G01D02*
X687280Y581347D01*
G01D02*
X688480D01*
G01D02*
X688920Y581787D01*
G01D02*
X690120D01*
G01D02*
X690560Y581347D01*
G01D02*
X691760D01*
G01D02*
X692200Y581787D01*
G01D02*
X693400D01*
G01D02*
X693840Y581347D01*
G01D02*
X695040D01*
G01D02*
X695480Y581787D01*
G01D02*
X696680D01*
G01D02*
X697120Y581347D01*
G01D02*
X698320D01*
G01D02*
X698760Y581787D01*
G01D02*
X699960D01*
G01D02*
X700400Y581347D01*
G01D02*
X750400D01*
G01X643905Y580047D02*
X770343D01*
G01X712619Y345160D02*
X713059Y345600D01*
G01X714300D02*
X714740Y345160D01*
G01D02*
X770646D01*
G01D02*
G03X771353Y345453I0J999D01*
G01X780514Y342540D02*
X773093D01*
G01D02*
G02X771500Y343200I0J2252D01*
G01D02*
G03X769907Y343860I-1593J-1592D01*
G01X713059Y345600D02*
X714300D01*
G01X771353Y345453D02*
X772087Y346187D01*
G01D02*
G02X772794Y346480I707J-706D01*
G01D02*
X780514D01*
G01X769899Y360921D02*
G03X771473Y361573I0J2226D01*
G01D02*
G02X773047Y362225I1574J-1574D01*
G01D02*
X780514D01*
G01Y358290D02*
X773251D01*
G01D02*
G02X771645Y358956I1J2272D01*
G01D02*
X771644Y358957D01*
G01D02*
G03X770039Y359621I-1605J-1608D01*
G01X711959Y384994D02*
X713160D01*
G01D02*
X713600Y384555D01*
G01D02*
X713601Y384554D01*
G01D02*
X769938D01*
G01D02*
G03X771502Y385202I0J2211D01*
G01D02*
G02X773066Y385850I1564J-1563D01*
G01D02*
X780514D01*
G01X769796Y383254D02*
G02X771418Y382582I0J-2294D01*
G01D02*
G03X773040Y381910I1622J1622D01*
G01D02*
X780514D01*
G01X769945Y400277D02*
G03X771536Y400936I0J2250D01*
G01D02*
G02X773127Y401595I1591J-1591D01*
G01D02*
X780514D01*
G01Y397660D02*
X773071D01*
G01D02*
G02X771482Y398318I0J2248D01*
G01D02*
G03X769892Y398977I-1590J-1589D01*
G01X713300Y414725D02*
X769942D01*
G01D02*
G02X771534Y414065I0J-2250D01*
G01D02*
X771535D01*
G01D02*
G03X773128Y413405I1593J1592D01*
G01D02*
X780514D01*
G01X723809Y466173D02*
X722676Y465040D01*
G01D02*
X722215Y464578D01*
G01D02*
G03X721753Y463464I1114J-1115D01*
G01D02*
Y462225D01*
G01D02*
G03X722122Y461334I1260J0D01*
G01D02*
X726122Y457334D01*
G01D02*
G03X728464Y456364I2342J2342D01*
G01D02*
X733292D01*
G01D02*
G03X735231Y457167I0J2742D01*
G01X719709Y462073D02*
Y461908D01*
G01D02*
X720452Y461164D01*
G01D02*
X725202Y456414D01*
G01D02*
X725203Y456415D01*
G01D02*
G03X728465Y455064I3261J3261D01*
G01D02*
X732543D01*
G01D02*
G02X735191Y453967I0J-3745D01*
G01X740309Y482873D02*
X739462Y482026D01*
G01D02*
G03X738402Y479467I2559J-2559D01*
G01D02*
Y479112D01*
G01D02*
G03X738963Y477758I1915J0D01*
G01D02*
X738964Y477757D01*
G01D02*
G03X739331Y477416I4582J4563D01*
G01D02*
X739332Y477417D01*
G01D02*
G03X742622Y475928I4205J4912D01*
G01D02*
G03X743533Y475863I915J6402D01*
G01D02*
G03X743535Y475864I-2883J5768D01*
G01D02*
X745578D01*
G01D02*
G03X746845Y476389I0J1792D01*
G01X736259Y478623D02*
X738048Y476834D01*
G01D02*
G03X741535Y474825I5480J5480D01*
G01D02*
G03X742439Y474641I1998J7505D01*
G01D02*
G03X743534Y474564I1091J7690D01*
G01D02*
X744900D01*
G01D02*
G02X745873Y474161I0J-1376D01*
G01D02*
X746845Y473189D01*
G01X736209Y478673D02*
X736259Y478623D01*
G01X713299Y416025D02*
X770482D01*
G01D02*
G03X771537Y416462I0J1492D01*
G01D02*
X772037Y416962D01*
G01D02*
G02X772962Y417345I925J-925D01*
G01D02*
X780514D01*
G01X716065Y429034D02*
X717214Y430182D01*
G01D02*
X717391Y430360D01*
G01D02*
G02X720800Y431772I3408J-3406D01*
G01D02*
X770040D01*
G01D02*
G03X771631Y432431I0J2250D01*
G01D02*
G02X773222Y433090I1591J-1591D01*
G01D02*
X780514D01*
G01X718135Y429264D02*
X718312Y429442D01*
G01D02*
G02X720800Y430472I2487J-2488D01*
G01D02*
X769897D01*
G01D02*
G02X771486Y429814I0J-2248D01*
G01D02*
G03X773077Y429155I1591J1591D01*
G01D02*
X780514D01*
G01X716750Y437850D02*
G02X720733Y439500I3983J-3983D01*
G01D02*
X757757D01*
G01D02*
G03X760938Y440818I-1J4500D01*
G01D02*
X766324Y446204D01*
G01D02*
G02X769506Y447522I3182J-3182D01*
G01D02*
X771090D01*
G01D02*
G03X772681Y448181I0J2250D01*
G01D02*
G02X774272Y448840I1591J-1591D01*
G01D02*
X780514D01*
G01X717919Y437180D02*
G02X720381Y438200I2462J-2462D01*
G01D02*
X757758D01*
G01D02*
G03X761858Y439898I-1J5801D01*
G01D02*
X767244Y445284D01*
G01D02*
G02X769506Y446222I2263J-2262D01*
G01D02*
X771047D01*
G01D02*
G02X772637Y445563I0J-2248D01*
G01D02*
G03X774226Y444905I1589J1590D01*
G01D02*
X780514D01*
G01X715509Y457973D02*
G03X715115Y457810I0J-558D01*
G01D02*
X714599Y457294D01*
G01D02*
G03X713562Y454790I2505J-2504D01*
G01D02*
Y453964D01*
G01D02*
G03X713968Y452984I1386J0D01*
G01D02*
X714697Y452255D01*
G01D02*
X717263Y449665D01*
G01D02*
G03X719316Y448814I2054J2054D01*
G01D02*
X728523D01*
G01D02*
X729009Y449300D01*
G01D02*
X730209D01*
G01D02*
X730695Y448814D01*
G01D02*
X731895D01*
G01D02*
X732381Y449300D01*
G01D02*
X733581D01*
G01D02*
X734067Y448814D01*
G01D02*
X735267D01*
G01D02*
X735753Y449300D01*
G01D02*
X736953D01*
G01D02*
X737439Y448814D01*
G01D02*
X738639D01*
G01D02*
X739125Y449300D01*
G01D02*
X740325D01*
G01D02*
X740811Y448814D01*
G01D02*
X750577D01*
G01D02*
G03X756468Y451254I0J8331D01*
G01D02*
X765393Y460179D01*
G01D02*
X765599Y460387D01*
G01D02*
G02X768182Y462243I6961J-6962D01*
G01D02*
G02X769340Y462728I4374J-8819D01*
G01D02*
G02X769906Y462905I3220J-9303D01*
G01D02*
G02X770321Y463011I2643J-9483D01*
G01D02*
G03X772011Y463711I0J2390D01*
G01D02*
X772300Y464000D01*
G01D02*
G02X773724Y464590I1424J-1424D01*
G01D02*
X780514D01*
G01X713778Y451334D02*
X716331Y448757D01*
G01D02*
X716343Y448745D01*
G01D02*
G03X719316Y447514I2973J2974D01*
G01D02*
X750577D01*
G01D02*
G03X757388Y450335I1J9631D01*
G01D02*
X766314Y459261D01*
G01D02*
X766520Y459468D01*
G01D02*
G02X768761Y461078I6040J-6043D01*
G01D02*
G02X769766Y461499I3797J-7654D01*
G01D02*
X770495D01*
G01D02*
G02X771700Y461000I0J-1704D01*
G01D02*
G03X772545Y460650I845J845D01*
G01D02*
X780514D01*
G01X732109Y474573D02*
X730735Y473200D01*
G01D02*
G03X730203Y471914I1286J-1285D01*
G01D02*
Y470511D01*
G01D02*
G03X730693Y469328I1673J0D01*
G01D02*
X731420Y468601D01*
G01D02*
G03X733617Y467723I2121J2119D01*
G01D02*
X733869D01*
G01D02*
Y467722D01*
G01D02*
G03X733870Y467723I-2358J2359D01*
G01D02*
X754299D01*
G01D02*
G03X759054Y469692I1J6724D01*
G01D02*
X759948Y470587D01*
G01D02*
X765934Y476573D01*
G01D02*
G02X769276Y478615I5900J-5900D01*
G01D02*
G02X769784Y478761I2558J-7942D01*
G01D02*
X771217D01*
G01D02*
G03X771835Y479017I0J874D01*
G01D02*
X772559Y479741D01*
G01D02*
G02X773993Y480335I1434J-1434D01*
G01D02*
X780514D01*
G01X727959Y470223D02*
X728483Y469698D01*
G01D02*
X730500Y467681D01*
G01D02*
G03X733539Y466422I3039J3039D01*
G01D02*
X733869D01*
G01D02*
Y466423D01*
G01D02*
X734853D01*
G01D02*
X735262Y466014D01*
G01D02*
X736253D01*
G01D02*
X736662Y466423D01*
G01D02*
X737653D01*
G01D02*
X738062Y466014D01*
G01D02*
X739053D01*
G01D02*
X739462Y466423D01*
G01D02*
X740453D01*
G01D02*
X740862Y466014D01*
G01D02*
X741853D01*
G01D02*
X742262Y466423D01*
G01D02*
X743253D01*
G01D02*
X743662Y466014D01*
G01D02*
X744653D01*
G01D02*
X745062Y466423D01*
G01D02*
X746053D01*
G01D02*
X746462Y466014D01*
G01D02*
X747453D01*
G01D02*
X747862Y466423D01*
G01D02*
X754299D01*
G01D02*
G03X759974Y468772I2J8025D01*
G01D02*
X760868Y469667D01*
G01D02*
X766854Y475653D01*
G01D02*
Y475654D01*
G01D02*
G02X769675Y477378I4981J-4981D01*
G01D02*
X771747D01*
G01D02*
G02X772476Y477076I0J-1031D01*
G01D02*
G03X774108Y476400I1632J1632D01*
G01D02*
X780514D01*
G01X732759Y478623D02*
X733803Y479667D01*
G01D02*
G03Y481014I-674J673D01*
G01D02*
G03X732574Y481523I-1229J-1229D01*
G01X728459Y474323D02*
X728659Y474523D01*
G01X724459Y470223D02*
X725403Y471167D01*
G01D02*
G03Y472714I-774J774D01*
G01D02*
G03X724657Y473023I-746J-746D01*
G01X723809Y462673D02*
G02X725544Y461955I1J-2453D01*
G01D02*
X726589Y460909D01*
G01X721445Y455789D02*
X720002Y457232D01*
G01D02*
G02X719709Y457939I706J707D01*
G01D02*
Y458573D01*
G01X743520Y478297D02*
G03X740922Y479373I-2598J-2598D01*
G01D02*
X740309D01*
G01X736209Y475173D02*
X736361D01*
G01D02*
X738745Y472789D01*
G01X715509Y454473D02*
G03X715933Y453448I1449J-1D01*
G01D02*
X716516Y452866D01*
G01D02*
X717993Y451389D01*
G01X712806Y449895D02*
X713075Y449625D01*
G01D02*
X713400Y449300D01*
G01D02*
G02X713845Y448226I-1074J-1074D01*
G01D02*
Y447289D01*
G01X732109Y471073D02*
X732422D01*
G01D02*
G02X735259Y469898I0J-4012D01*
G01X727909Y466773D02*
X728919D01*
G01D02*
G02X729699Y466450I0J-1103D01*
G01D02*
X731751Y464398D01*
G01X720359Y466123D02*
G02X719584Y465802I-775J775D01*
G01X716477Y464502D02*
G02X717411Y464115I0J-1321D01*
G01D02*
G02X717203Y462967I-931J-424D01*
G01D02*
X716259Y462023D01*
G01X714502Y501430D02*
X741322Y528251D01*
G01D02*
G02X746023Y530197I4700J-4702D01*
G01D02*
X770565D01*
G01D02*
G03X772156Y530856I0J2250D01*
G01D02*
G02X773747Y531515I1591J-1591D01*
G01D02*
X780514D01*
G01X715422Y500510D02*
X742242Y527331D01*
G01D02*
G02X746023Y528897I3781J-3781D01*
G01D02*
X770537D01*
G01D02*
G02X771845Y528355I0J-1849D01*
G01D02*
X771961Y528238D01*
G01D02*
G03X773551Y527580I1589J1590D01*
G01D02*
X780514D01*
G01X725611Y491430D02*
G03X726948Y491984I0J1890D01*
G01D02*
X727502Y492538D01*
G01D02*
G02X733591Y495060I6090J-6091D01*
G01D02*
X769938D01*
G01D02*
G03X769970I16J1502D01*
G01D02*
G03X770977Y495477I0J1424D01*
G01D02*
X771000Y495500D01*
G01D02*
G02X772412Y496085I1412J-1412D01*
G01D02*
X780514D01*
G01X725611Y490130D02*
G03X727868Y491064I1J3191D01*
G01D02*
X728422Y491618D01*
G01D02*
G02X733592Y493760I5171J-5171D01*
G01D02*
X770498D01*
G01D02*
G02X771338Y493412I0J-1188D01*
G01D02*
G02X771948Y492952I-1339J-2410D01*
G01D02*
G03X773896Y492145I1948J1948D01*
G01D02*
X780514D01*
G01X750400Y581347D02*
X750840Y581787D01*
G01D02*
X752040D01*
G01D02*
X752480Y581347D01*
G01D02*
X753680D01*
G01D02*
X754120Y581787D01*
G01D02*
X755320D01*
G01D02*
X755760Y581347D01*
G01D02*
X756960D01*
G01D02*
X757400Y581787D01*
G01D02*
X758600D01*
G01D02*
X759040Y581347D01*
G01D02*
X760240D01*
G01D02*
X760680Y581787D01*
G01D02*
X761880D01*
G01D02*
X762320Y581347D01*
G01D02*
X763520D01*
G01D02*
X763960Y581787D01*
G01D02*
X765160D01*
G01D02*
X765600Y581347D01*
G01D02*
X770639D01*
G01D02*
G03X771426Y581673I0J1113D01*
G01D02*
X771726Y581973D01*
G01D02*
G02X773481Y582700I1755J-1755D01*
G01D02*
X780514D01*
G01X770343Y580047D02*
G02X771393Y579778I-3J-2196D01*
G01D02*
G02X771458Y579742I-1031J-1939D01*
G01D02*
G02X771896Y579404I-1112J-1894D01*
G01D02*
G03X773451Y578760I1555J1555D01*
G01D02*
X780514D01*
G01X759051Y601789D02*
G02X765426Y599149I0J-9017D01*
G01D02*
X766322Y598253D01*
G01D02*
G03X769040Y597127I2718J2718D01*
G01D02*
X770195D01*
G01D02*
G03X771786Y597786I0J2250D01*
G01D02*
G02X773377Y598445I1591J-1591D01*
G01D02*
X780514D01*
G01X759050Y600489D02*
G02X764506Y598229I0J-7716D01*
G01D02*
X765402Y597333D01*
G01D02*
G03X769039Y595827I3637J3639D01*
G01D02*
X770242D01*
G01D02*
G02X771832Y595168I0J-2248D01*
G01D02*
G03X773421Y594510I1589J1590D01*
G01D02*
X780514D01*
G01X759100Y612477D02*
X759623Y613000D01*
G01D02*
X760600D01*
G01D02*
X761123Y612477D01*
G01D02*
X770236D01*
G01D02*
G03X771711Y613088I0J2086D01*
G01D02*
X772161Y613538D01*
G01D02*
G02X773747Y614195I1586J-1586D01*
G01D02*
X780514D01*
G01X770574Y611177D02*
G02X771682Y610718I0J-1567D01*
G01D02*
G03X772788Y610260I1106J1106D01*
G01D02*
X780514D01*
G01X771975Y626925D02*
G03X774196Y626005I2221J2221D01*
G01D02*
X780514D01*
G01X770728Y629145D02*
G03X771534Y629479I0J1140D01*
G01D02*
G02X772659Y629945I1125J-1125D01*
G01D02*
X780514D01*
G01X769754Y627845D02*
G02X771332Y627419I-1J-3141D01*
G01D02*
G02X771975Y626925I-1576J-2717D01*
G01X769161Y643447D02*
G03X771868Y644568I0J3829D01*
G01D02*
G02X774577Y645690I2709J-2709D01*
G01D02*
X780514D01*
G01X771054Y642147D02*
G02X771609Y641917I0J-785D01*
G01D02*
G03X772000Y641755I391J391D01*
G01D02*
X780514D01*
G54D11*
G01X-1003937Y-3937D02*
G03X-1000000Y-7874I3937J0D01*
G01X-1031496Y-31496D02*
G03X-1027559Y-35433I3937J0D01*
G01X-986221Y-7874D02*
G03Y0I0J3937D01*
G01Y-7874D02*
X-1000000D01*
G01X-1027559Y-35433D02*
X791338D01*
G01X-1031496Y95866D02*
Y-31496D01*
G01X-996063Y3937D02*
G03X-992126Y0I3937J0D01*
G01X-996063Y39370D02*
G03X-1003937I-3937J0D01*
G01X-996063Y3937D02*
G03X-992126Y0I3937J0D01*
G01D02*
X-318898D01*
G01D02*
X-992126D01*
G01X-955512D02*
X-986221D01*
G01X-996063Y3937D02*
Y103740D01*
G01Y39370D02*
Y70079D01*
G01X-1003937Y-3937D02*
Y39370D01*
G01X-1027559Y99803D02*
G03X-1031496Y95866I0J-3937D01*
G01X-1003937D02*
G03X-1007874Y99803I-3937J0D01*
G01X-996063Y103740D02*
G03X-1000000Y107677I-3937J0D01*
G01X-1003937Y70079D02*
G03X-996063I3937J0D01*
G01X-1029528Y107677D02*
X-1000000D01*
G01X-1007874Y99803D02*
X-1027559D01*
G01X-1003937Y70079D02*
Y95866D01*
G01X-1031496Y109646D02*
X-1029528Y107677D01*
G01X-1031496Y109646D02*
Y134055D01*
G01X-1002166Y136024D02*
G03Y143504I0J3740D01*
G01X-1000000Y187599D02*
G03X-996063Y191536I0J3937D01*
G01X-1029528Y187599D02*
X-1000000D01*
G01X-1029528Y143504D02*
X-1002166D01*
G01X-1029528Y136024D02*
X-1002166D01*
G01X-1029528D02*
X-1031496Y134055D01*
G01X-1029528Y187599D02*
X-1031496Y185630D01*
G01Y145473D02*
X-1029528Y143504D01*
G01X-996063Y261221D02*
Y191536D01*
G01X-1031496Y145473D02*
Y185630D01*
G01X-996063Y261221D02*
G03X-1000000Y265158I-3937J0D01*
G01X-1029528D02*
X-1000000D01*
G01X-1031496Y267126D02*
X-1029528Y265158D01*
G01X-1031496Y267126D02*
Y543504D01*
G01X-1002166Y545473D02*
G03Y552953I0J3740D01*
G01X-1029528D02*
X-1002166D01*
G01X-1029528Y545473D02*
X-1002166D01*
G01X-1031496Y554922D02*
X-1029528Y552953D01*
G01Y545473D02*
X-1031496Y543504D01*
G01Y554922D02*
Y595079D01*
G01X-1007874Y604922D02*
G03X-1003937Y608859I0J3937D01*
G01X-1031496D02*
G03X-1027559Y604922I3937J0D01*
G01X-1000000Y597048D02*
G03X-996063Y600985I0J3937D01*
G01X-1027559Y604922D02*
X-1007874D01*
G01X-1029528Y597048D02*
X-1000000D01*
G01X-1029528D02*
X-1031496Y595079D01*
G01X-996063Y921260D02*
Y600985D01*
G01X-1003937Y608859D02*
Y708662D01*
G01X-1031496Y956693D02*
Y608859D01*
G01X-1003937Y739370D02*
G03X-996063I3937J0D01*
G01Y708662D02*
G03X-1003937I-3937J0D01*
G01X-996063D02*
Y739370D01*
G01X-1003937D02*
Y929134D01*
G01X-992126Y925197D02*
G03X-996063Y921260I0J-3937D01*
G01X-1000000Y933071D02*
G03X-1003937Y929134I0J-3937D01*
G01X-986221Y925197D02*
G03Y933071I0J3937D01*
G01X-1027559Y960630D02*
G03X-1031496Y956693I0J-3937D01*
G01X-992126Y925197D02*
G03X-996063Y921260I0J-3937D01*
G01X791338Y960630D02*
X-1027559D01*
G01X-1000000Y933071D02*
X-986221D01*
G01X-992126Y925197D02*
X-240158D01*
G01X-986221D02*
X-955512D01*
G01X-992126D02*
X-240158D01*
G01X-955512Y0D02*
G03Y-7874I0J-3937D01*
G01X-769685D02*
X-955512D01*
G01Y933071D02*
G03Y925197I0J-3937D01*
G01Y933071D02*
X-750000D01*
G01X-769685Y-7874D02*
G03Y0I0J3937D01*
G01X-738977D02*
X-769685D01*
G01X-738977D02*
G03Y-7874I0J-3937D01*
G01X-522835D02*
X-738977D01*
G01X-719292Y933071D02*
G03Y925197I0J-3937D01*
G01X-750000D02*
G03Y933071I0J3937D01*
G01X-719292D02*
X-512992D01*
G01X-750000Y925197D02*
X-719292D01*
G01X-574792Y-69796D02*
Y-81796D01*
G01X-577092Y-69796D02*
X-572492D01*
G01X-570492Y-81796D02*
Y-69796D01*
G01Y-75596D02*
X-569992Y-74596D01*
X-569492Y-73996D01*
X-568692Y-73796D01*
X-568092Y-73996D01*
X-567392Y-74796D01*
X-567092Y-75996D01*
Y-81796D01*
G01X-562792Y-73796D02*
Y-81796D01*
G01Y-70596D02*
X-562992Y-70396D01*
Y-69996D01*
X-562792Y-69796D01*
X-562592Y-69996D01*
Y-70396D01*
X-562792Y-70596D01*
G01X-558292Y-80396D02*
X-557792Y-81196D01*
X-557092Y-81796D01*
X-556492D01*
X-555892Y-81396D01*
X-555492Y-80796D01*
X-555292Y-79996D01*
X-555392Y-78796D01*
X-555792Y-78196D01*
X-557592Y-76996D01*
X-557992Y-75596D01*
X-557792Y-74596D01*
X-557392Y-73996D01*
X-556792Y-73796D01*
X-556192Y-73996D01*
X-555592Y-74596D01*
G01X-546192Y-84796D02*
X-545492Y-85596D01*
X-544692Y-85796D01*
X-543992Y-85596D01*
X-543392Y-84596D01*
X-542992Y-83196D01*
Y-73796D01*
G01Y-75396D02*
X-543392Y-74596D01*
X-543992Y-73996D01*
X-544692Y-73796D01*
X-545492Y-74196D01*
X-545992Y-74996D01*
X-546392Y-76396D01*
X-546592Y-77796D01*
X-546492Y-78996D01*
X-546092Y-80396D01*
X-545492Y-81396D01*
X-544692Y-81796D01*
X-544092Y-81596D01*
X-543392Y-80796D01*
X-542992Y-79996D01*
G01X-540292Y-76396D02*
X-537092D01*
X-537392Y-74996D01*
X-537892Y-74196D01*
X-538592Y-73796D01*
X-539292Y-73996D01*
X-539892Y-74596D01*
X-540292Y-75996D01*
X-540492Y-77196D01*
Y-78396D01*
X-540292Y-79596D01*
X-539792Y-80796D01*
X-539192Y-81596D01*
X-538492Y-81796D01*
X-537792Y-81396D01*
X-537092Y-80196D01*
G01X-534192Y-81796D02*
Y-73796D01*
G01Y-75396D02*
X-533692Y-74596D01*
X-533192Y-73996D01*
X-532492Y-73796D01*
X-531992Y-73996D01*
X-531392Y-74596D01*
G01X-528592Y-81796D02*
Y-69796D01*
G01Y-75796D02*
X-528092Y-74596D01*
X-527492Y-73996D01*
X-526892Y-73796D01*
X-525992Y-74196D01*
X-525392Y-74996D01*
X-524992Y-76396D01*
Y-77996D01*
X-525192Y-79596D01*
X-525592Y-80796D01*
X-526292Y-81596D01*
X-526892Y-81796D01*
X-527492Y-81596D01*
X-528092Y-80996D01*
X-528592Y-79996D01*
G01X-522292Y-76396D02*
X-519092D01*
X-519392Y-74996D01*
X-519892Y-74196D01*
X-520592Y-73796D01*
X-521292Y-73996D01*
X-521892Y-74596D01*
X-522292Y-75996D01*
X-522492Y-77196D01*
Y-78396D01*
X-522292Y-79596D01*
X-521792Y-80796D01*
X-521192Y-81596D01*
X-520492Y-81796D01*
X-519792Y-81396D01*
X-519092Y-80196D01*
G01X-516192Y-81796D02*
Y-73796D01*
G01Y-75396D02*
X-515692Y-74596D01*
X-515192Y-73996D01*
X-514492Y-73796D01*
X-513992Y-73996D01*
X-513392Y-74596D01*
G01X-502792Y-73796D02*
Y-81796D01*
G01Y-70596D02*
X-502992Y-70396D01*
Y-69996D01*
X-502792Y-69796D01*
X-502592Y-69996D01*
Y-70396D01*
X-502792Y-70596D01*
G01X-498292Y-80396D02*
X-497792Y-81196D01*
X-497092Y-81796D01*
X-496492D01*
X-495892Y-81396D01*
X-495492Y-80796D01*
X-495292Y-79996D01*
X-495392Y-78796D01*
X-495792Y-78196D01*
X-497592Y-76996D01*
X-497992Y-75596D01*
X-497792Y-74596D01*
X-497392Y-73996D01*
X-496792Y-73796D01*
X-496192Y-73996D01*
X-495592Y-74596D01*
G01X-486392Y-84796D02*
X-485692Y-85596D01*
X-485092Y-85796D01*
X-484292Y-85396D01*
X-483692Y-84396D01*
X-483392Y-82596D01*
Y-73796D01*
G01Y-70596D02*
X-483592Y-70396D01*
Y-69996D01*
X-483392Y-69796D01*
X-483192Y-69996D01*
Y-70396D01*
X-483392Y-70596D01*
G01X-480492Y-73796D02*
Y-79396D01*
X-480092Y-80796D01*
X-479492Y-81596D01*
X-478792Y-81796D01*
X-478092Y-81596D01*
X-477492Y-80796D01*
X-477092Y-79396D01*
G01Y-81796D02*
Y-73796D01*
G01X-474292Y-80396D02*
X-473792Y-81196D01*
X-473092Y-81796D01*
X-472492D01*
X-471892Y-81396D01*
X-471492Y-80796D01*
X-471292Y-79996D01*
X-471392Y-78796D01*
X-471792Y-78196D01*
X-473592Y-76996D01*
X-473992Y-75596D01*
X-473792Y-74596D01*
X-473392Y-73996D01*
X-472792Y-73796D01*
X-472192Y-73996D01*
X-471592Y-74596D01*
G01X-466792Y-69796D02*
Y-81796D01*
G01X-468192Y-73796D02*
X-465392D01*
G01X-455392Y-81796D02*
Y-71596D01*
X-455192Y-70596D01*
X-454792Y-69996D01*
X-454192Y-69796D01*
X-453592Y-70196D01*
X-453292Y-71196D01*
G01X-454492Y-74596D02*
X-456492D01*
G01X-448792Y-81796D02*
X-449392Y-81596D01*
X-449992Y-80796D01*
X-450392Y-79396D01*
X-450592Y-77796D01*
X-450392Y-76196D01*
X-449992Y-74796D01*
X-449392Y-73996D01*
X-448792Y-73796D01*
X-448192Y-73996D01*
X-447592Y-74796D01*
X-447192Y-76196D01*
X-447092Y-77796D01*
X-447192Y-79396D01*
X-447592Y-80796D01*
X-448192Y-81596D01*
X-448792Y-81796D01*
G01X-444192D02*
Y-73796D01*
G01Y-75396D02*
X-443692Y-74596D01*
X-443192Y-73996D01*
X-442492Y-73796D01*
X-441992Y-73996D01*
X-441392Y-74596D01*
G01X-432892Y-85396D02*
X-432292Y-85796D01*
X-431492Y-85396D01*
X-430992Y-84596D01*
X-430592Y-83596D01*
X-429992Y-80396D01*
X-428692Y-73796D01*
G01X-431892D02*
X-429992Y-80396D01*
G01X-424792Y-81796D02*
X-425392Y-81596D01*
X-425992Y-80796D01*
X-426392Y-79396D01*
X-426592Y-77796D01*
X-426392Y-76196D01*
X-425992Y-74796D01*
X-425392Y-73996D01*
X-424792Y-73796D01*
X-424192Y-73996D01*
X-423592Y-74796D01*
X-423192Y-76196D01*
X-423092Y-77796D01*
X-423192Y-79396D01*
X-423592Y-80796D01*
X-424192Y-81596D01*
X-424792Y-81796D01*
G01X-420492Y-73796D02*
Y-79396D01*
X-420092Y-80796D01*
X-419492Y-81596D01*
X-418792Y-81796D01*
X-418092Y-81596D01*
X-417492Y-80796D01*
X-417092Y-79396D01*
G01Y-81796D02*
Y-73796D01*
G01X-408192Y-81796D02*
Y-73796D01*
G01Y-75396D02*
X-407692Y-74596D01*
X-407192Y-73996D01*
X-406492Y-73796D01*
X-405992Y-73996D01*
X-405392Y-74596D01*
G01X-402292Y-76396D02*
X-399092D01*
X-399392Y-74996D01*
X-399892Y-74196D01*
X-400592Y-73796D01*
X-401292Y-73996D01*
X-401892Y-74596D01*
X-402292Y-75996D01*
X-402492Y-77196D01*
Y-78396D01*
X-402292Y-79596D01*
X-401792Y-80796D01*
X-401192Y-81596D01*
X-400492Y-81796D01*
X-399792Y-81396D01*
X-399092Y-80196D01*
G01X-395392Y-81796D02*
Y-71596D01*
X-395192Y-70596D01*
X-394792Y-69996D01*
X-394192Y-69796D01*
X-393592Y-70196D01*
X-393292Y-71196D01*
G01X-394492Y-74596D02*
X-396492D01*
G01X-390292Y-76396D02*
X-387092D01*
X-387392Y-74996D01*
X-387892Y-74196D01*
X-388592Y-73796D01*
X-389292Y-73996D01*
X-389892Y-74596D01*
X-390292Y-75996D01*
X-390492Y-77196D01*
Y-78396D01*
X-390292Y-79596D01*
X-389792Y-80796D01*
X-389192Y-81596D01*
X-388492Y-81796D01*
X-387792Y-81396D01*
X-387092Y-80196D01*
G01X-384192Y-81796D02*
Y-73796D01*
G01Y-75396D02*
X-383692Y-74596D01*
X-383192Y-73996D01*
X-382492Y-73796D01*
X-381992Y-73996D01*
X-381392Y-74596D01*
G01X-378292Y-76396D02*
X-375092D01*
X-375392Y-74996D01*
X-375892Y-74196D01*
X-376592Y-73796D01*
X-377292Y-73996D01*
X-377892Y-74596D01*
X-378292Y-75996D01*
X-378492Y-77196D01*
Y-78396D01*
X-378292Y-79596D01*
X-377792Y-80796D01*
X-377192Y-81596D01*
X-376492Y-81796D01*
X-375792Y-81396D01*
X-375092Y-80196D01*
G01X-372492Y-81796D02*
Y-73796D01*
G01Y-75796D02*
X-372092Y-74796D01*
X-371492Y-73996D01*
X-370692Y-73796D01*
X-369992Y-73996D01*
X-369392Y-74796D01*
X-369092Y-76196D01*
Y-81796D01*
G01X-363192Y-74796D02*
X-363892Y-73996D01*
X-364492Y-73796D01*
X-365292Y-74196D01*
X-365892Y-74996D01*
X-366292Y-76396D01*
X-366392Y-77796D01*
X-366292Y-79196D01*
X-365892Y-80396D01*
X-365292Y-81396D01*
X-364492Y-81796D01*
X-363792Y-81396D01*
X-363192Y-80596D01*
G01X-360292Y-76396D02*
X-357092D01*
X-357392Y-74996D01*
X-357892Y-74196D01*
X-358592Y-73796D01*
X-359292Y-73996D01*
X-359892Y-74596D01*
X-360292Y-75996D01*
X-360492Y-77196D01*
Y-78396D01*
X-360292Y-79596D01*
X-359792Y-80796D01*
X-359192Y-81596D01*
X-358492Y-81796D01*
X-357792Y-81396D01*
X-357092Y-80196D01*
G01X-346792Y-69796D02*
Y-81796D01*
G01X-348192Y-73796D02*
X-345392D01*
G01X-340792Y-81796D02*
X-341392Y-81596D01*
X-341992Y-80796D01*
X-342392Y-79396D01*
X-342592Y-77796D01*
X-342392Y-76196D01*
X-341992Y-74796D01*
X-341392Y-73996D01*
X-340792Y-73796D01*
X-340192Y-73996D01*
X-339592Y-74796D01*
X-339192Y-76196D01*
X-339092Y-77796D01*
X-339192Y-79396D01*
X-339592Y-80796D01*
X-340192Y-81596D01*
X-340792Y-81796D01*
G01X-329392D02*
Y-71596D01*
X-329192Y-70596D01*
X-328792Y-69996D01*
X-328192Y-69796D01*
X-327592Y-70196D01*
X-327292Y-71196D01*
G01X-328492Y-74596D02*
X-330492D01*
G01X-322792Y-73796D02*
Y-81796D01*
G01Y-70596D02*
X-322992Y-70396D01*
Y-69996D01*
X-322792Y-69796D01*
X-322592Y-69996D01*
Y-70396D01*
X-322792Y-70596D01*
G01X-318492Y-81796D02*
Y-73796D01*
G01Y-75796D02*
X-318092Y-74796D01*
X-317492Y-73996D01*
X-316692Y-73796D01*
X-315992Y-73996D01*
X-315392Y-74796D01*
X-315092Y-76196D01*
Y-81796D01*
G01X-308992Y-69796D02*
Y-81796D01*
G01Y-79996D02*
X-309392Y-80996D01*
X-309992Y-81596D01*
X-310692Y-81796D01*
X-311492Y-81396D01*
X-312092Y-80396D01*
X-312492Y-79196D01*
X-312592Y-77796D01*
X-312492Y-76396D01*
X-312092Y-75196D01*
X-311492Y-74196D01*
X-310692Y-73796D01*
X-309992Y-73996D01*
X-309492Y-74396D01*
X-308992Y-75196D01*
G01X-298792Y-69796D02*
Y-81796D01*
G01X-300192Y-73796D02*
X-297392D01*
G01X-294492Y-81796D02*
Y-69796D01*
G01Y-75596D02*
X-293992Y-74596D01*
X-293492Y-73996D01*
X-292692Y-73796D01*
X-292092Y-73996D01*
X-291392Y-74796D01*
X-291092Y-75996D01*
Y-81796D01*
G01X-288292Y-76396D02*
X-285092D01*
X-285392Y-74996D01*
X-285892Y-74196D01*
X-286592Y-73796D01*
X-287292Y-73996D01*
X-287892Y-74596D01*
X-288292Y-75996D01*
X-288492Y-77196D01*
Y-78396D01*
X-288292Y-79596D01*
X-287792Y-80796D01*
X-287192Y-81596D01*
X-286492Y-81796D01*
X-285792Y-81396D01*
X-285092Y-80196D01*
G01X-272992Y-69796D02*
Y-81796D01*
G01Y-79996D02*
X-273392Y-80996D01*
X-273992Y-81596D01*
X-274692Y-81796D01*
X-275492Y-81396D01*
X-276092Y-80396D01*
X-276492Y-79196D01*
X-276592Y-77796D01*
X-276492Y-76396D01*
X-276092Y-75196D01*
X-275492Y-74196D01*
X-274692Y-73796D01*
X-273992Y-73996D01*
X-273492Y-74396D01*
X-272992Y-75196D01*
G01X-268792Y-73796D02*
Y-81796D01*
G01Y-70596D02*
X-268992Y-70396D01*
Y-69996D01*
X-268792Y-69796D01*
X-268592Y-69996D01*
Y-70396D01*
X-268792Y-70596D01*
G01X-263392Y-81796D02*
Y-71596D01*
X-263192Y-70596D01*
X-262792Y-69996D01*
X-262192Y-69796D01*
X-261592Y-70196D01*
X-261292Y-71196D01*
G01X-262492Y-74596D02*
X-264492D01*
G01X-257392Y-81796D02*
Y-71596D01*
X-257192Y-70596D01*
X-256792Y-69996D01*
X-256192Y-69796D01*
X-255592Y-70196D01*
X-255292Y-71196D01*
G01X-256492Y-74596D02*
X-258492D01*
G01X-252292Y-76396D02*
X-249092D01*
X-249392Y-74996D01*
X-249892Y-74196D01*
X-250592Y-73796D01*
X-251292Y-73996D01*
X-251892Y-74596D01*
X-252292Y-75996D01*
X-252492Y-77196D01*
Y-78396D01*
X-252292Y-79596D01*
X-251792Y-80796D01*
X-251192Y-81596D01*
X-250492Y-81796D01*
X-249792Y-81396D01*
X-249092Y-80196D01*
G01X-246192Y-81796D02*
Y-73796D01*
G01Y-75396D02*
X-245692Y-74596D01*
X-245192Y-73996D01*
X-244492Y-73796D01*
X-243992Y-73996D01*
X-243392Y-74596D01*
G01X-240292Y-76396D02*
X-237092D01*
X-237392Y-74996D01*
X-237892Y-74196D01*
X-238592Y-73796D01*
X-239292Y-73996D01*
X-239892Y-74596D01*
X-240292Y-75996D01*
X-240492Y-77196D01*
Y-78396D01*
X-240292Y-79596D01*
X-239792Y-80796D01*
X-239192Y-81596D01*
X-238492Y-81796D01*
X-237792Y-81396D01*
X-237092Y-80196D01*
G01X-234492Y-81796D02*
Y-73796D01*
G01Y-75796D02*
X-234092Y-74796D01*
X-233492Y-73996D01*
X-232692Y-73796D01*
X-231992Y-73996D01*
X-231392Y-74796D01*
X-231092Y-76196D01*
Y-81796D01*
G01X-226792Y-69796D02*
Y-81796D01*
G01X-228192Y-73796D02*
X-225392D01*
G01X-220792D02*
Y-81796D01*
G01Y-70596D02*
X-220992Y-70396D01*
Y-69996D01*
X-220792Y-69796D01*
X-220592Y-69996D01*
Y-70396D01*
X-220792Y-70596D01*
G01X-212992Y-81796D02*
Y-73796D01*
G01Y-75196D02*
X-213392Y-74396D01*
X-213992Y-73996D01*
X-214692Y-73796D01*
X-215392Y-74196D01*
X-215992Y-74996D01*
X-216392Y-76196D01*
X-216592Y-77796D01*
X-216392Y-79396D01*
X-215992Y-80596D01*
X-215392Y-81396D01*
X-214692Y-81796D01*
X-213992Y-81596D01*
X-213392Y-80996D01*
X-212992Y-80196D01*
G01X-208792Y-81796D02*
Y-69796D01*
G01X-196792D02*
Y-81796D01*
G01X-198192Y-73796D02*
X-195392D01*
G01X-192192Y-81796D02*
Y-73796D01*
G01Y-75396D02*
X-191692Y-74596D01*
X-191192Y-73996D01*
X-190492Y-73796D01*
X-189992Y-73996D01*
X-189392Y-74596D01*
G01X-182992Y-81796D02*
Y-73796D01*
G01Y-75196D02*
X-183392Y-74396D01*
X-183992Y-73996D01*
X-184692Y-73796D01*
X-185392Y-74196D01*
X-185992Y-74996D01*
X-186392Y-76196D01*
X-186592Y-77796D01*
X-186392Y-79396D01*
X-185992Y-80596D01*
X-185392Y-81396D01*
X-184692Y-81796D01*
X-183992Y-81596D01*
X-183392Y-80996D01*
X-182992Y-80196D01*
G01X-177192Y-74796D02*
X-177892Y-73996D01*
X-178492Y-73796D01*
X-179292Y-74196D01*
X-179892Y-74996D01*
X-180292Y-76396D01*
X-180392Y-77796D01*
X-180292Y-79196D01*
X-179892Y-80396D01*
X-179292Y-81396D01*
X-178492Y-81796D01*
X-177792Y-81396D01*
X-177192Y-80596D01*
G01X-174292Y-76396D02*
X-171092D01*
X-171392Y-74996D01*
X-171892Y-74196D01*
X-172592Y-73796D01*
X-173292Y-73996D01*
X-173892Y-74596D01*
X-174292Y-75996D01*
X-174492Y-77196D01*
Y-78396D01*
X-174292Y-79596D01*
X-173792Y-80796D01*
X-173192Y-81596D01*
X-172492Y-81796D01*
X-171792Y-81396D01*
X-171092Y-80196D01*
G01X-168292Y-80396D02*
X-167792Y-81196D01*
X-167092Y-81796D01*
X-166492D01*
X-165892Y-81396D01*
X-165492Y-80796D01*
X-165292Y-79996D01*
X-165392Y-78796D01*
X-165792Y-78196D01*
X-167592Y-76996D01*
X-167992Y-75596D01*
X-167792Y-74596D01*
X-167392Y-73996D01*
X-166792Y-73796D01*
X-166192Y-73996D01*
X-165592Y-74596D01*
G01X-154792Y-73796D02*
Y-81796D01*
G01Y-70596D02*
X-154992Y-70396D01*
Y-69996D01*
X-154792Y-69796D01*
X-154592Y-69996D01*
Y-70396D01*
X-154792Y-70596D01*
G01X-150492Y-81796D02*
Y-73796D01*
G01Y-75796D02*
X-150092Y-74796D01*
X-149492Y-73996D01*
X-148692Y-73796D01*
X-147992Y-73996D01*
X-147392Y-74796D01*
X-147092Y-76196D01*
Y-81796D01*
G01X-136792D02*
Y-69796D01*
G01X-128992Y-81796D02*
Y-73796D01*
G01Y-75196D02*
X-129392Y-74396D01*
X-129992Y-73996D01*
X-130692Y-73796D01*
X-131392Y-74196D01*
X-131992Y-74996D01*
X-132392Y-76196D01*
X-132592Y-77796D01*
X-132392Y-79396D01*
X-131992Y-80596D01*
X-131392Y-81396D01*
X-130692Y-81796D01*
X-129992Y-81596D01*
X-129392Y-80996D01*
X-128992Y-80196D01*
G01X-126892Y-85396D02*
X-126292Y-85796D01*
X-125492Y-85396D01*
X-124992Y-84596D01*
X-124592Y-83596D01*
X-123992Y-80396D01*
X-122692Y-73796D01*
G01X-125892D02*
X-123992Y-80396D01*
G01X-120292Y-76396D02*
X-117092D01*
X-117392Y-74996D01*
X-117892Y-74196D01*
X-118592Y-73796D01*
X-119292Y-73996D01*
X-119892Y-74596D01*
X-120292Y-75996D01*
X-120492Y-77196D01*
Y-78396D01*
X-120292Y-79596D01*
X-119792Y-80796D01*
X-119192Y-81596D01*
X-118492Y-81796D01*
X-117792Y-81396D01*
X-117092Y-80196D01*
G01X-114192Y-81796D02*
Y-73796D01*
G01Y-75396D02*
X-113692Y-74596D01*
X-113192Y-73996D01*
X-112492Y-73796D01*
X-111992Y-73996D01*
X-111392Y-74596D01*
G01X-100792Y-69796D02*
Y-81796D01*
G01X-103092Y-69796D02*
X-98492D01*
G01X-94792Y-81796D02*
X-95592Y-81596D01*
X-96292Y-80796D01*
X-96892Y-79596D01*
X-97292Y-78196D01*
X-97492Y-76596D01*
Y-74996D01*
X-97292Y-73396D01*
X-96892Y-71996D01*
X-96292Y-70796D01*
X-95592Y-69996D01*
X-94792Y-69796D01*
X-93992Y-69996D01*
X-93292Y-70796D01*
X-92692Y-71996D01*
X-92292Y-73396D01*
X-92092Y-74996D01*
Y-76596D01*
X-92292Y-78196D01*
X-92692Y-79596D01*
X-93292Y-80796D01*
X-93992Y-81596D01*
X-94792Y-81796D01*
G01X-90792D02*
Y-69796D01*
X-88392D01*
X-87592Y-70396D01*
X-86992Y-71796D01*
X-86792Y-73396D01*
X-86992Y-74996D01*
X-87492Y-76196D01*
X-88392Y-76796D01*
X-90792D01*
G01X-522835Y-7874D02*
G03Y0I0J3937D01*
G01X-492126D02*
G03Y-7874I0J-3937D01*
G01X-365355D02*
X-492126D01*
G01Y0D02*
X-522835D01*
G01X-482284Y933071D02*
G03Y925197I0J-3937D01*
G01X-512992D02*
G03Y933071I0J3937D01*
G01Y925197D02*
X-482284D01*
G01Y933071D02*
X-316142D01*
G01X-365355Y-7874D02*
G03Y0I0J3937D01*
G01X-334646D02*
X-365355D01*
G01X-311024Y-7874D02*
G03X-307087Y-3937I0J3937D01*
G01X-334646Y0D02*
G03Y-7874I0J-3937D01*
G01X-311024D02*
X-334646D01*
G01X-318898Y0D02*
G03X-314961Y3937I0J3937D01*
G01X-274410Y31595D02*
G03X-270473Y35532I0J3937D01*
G01X-303150Y31595D02*
G03X-307087Y27658I0J-3937D01*
G01X-318898Y0D02*
G03X-314961Y3937I0J3937D01*
G01X-307087Y27658D02*
Y-3937D01*
G01X-314961Y133859D02*
Y3937D01*
G01Y133859D02*
Y3937D01*
G01X-274410Y31595D02*
X-303150D01*
G01X-311024Y137796D02*
G03X-314961Y133859I0J-3937D01*
G01X-311024Y137796D02*
G03X-314961Y133859I0J-3937D01*
G01X-240158Y137796D02*
X-311024D01*
G01X-240158D02*
X-311024D01*
G01X-285433Y933071D02*
G03Y925197I0J-3937D01*
G01X-316142D02*
G03Y933071I0J3937D01*
G01X-285433D02*
X-224410D01*
G01X-316142Y925197D02*
X-285433D01*
G01X-270473Y125985D02*
Y35532D01*
G01X-266536Y129922D02*
G03X-270473Y125985I0J-3937D01*
G01X-260630Y129922D02*
G03Y137796I0J3937D01*
G01X-244882D02*
G03Y129922I0J-3937D01*
G01X-240158D02*
G03X-228347Y141733I0J11811D01*
G01X-260630Y129922D02*
X-266536D01*
G01X-240158D02*
X-244882D01*
G01X-240158Y137796D02*
G03X-236221Y141733I0J3937D01*
G01X-240158Y137796D02*
G03X-236221Y141733I0J3937D01*
G01X-228347Y368701D02*
Y141733D01*
G01X-236221Y413386D02*
Y141733D01*
G01X-244882Y137796D02*
X-260630D01*
G01X-204725Y409449D02*
G03X-208662Y405512I0J-3937D01*
G01X-232284Y417323D02*
G03X-236221Y413386I0J-3937D01*
G01X-232284Y417323D02*
G03X-236221Y413386I0J-3937D01*
G01X-212599Y372638D02*
G03X-208662Y376575I0J3937D01*
G01X-224410Y372638D02*
G03X-228347Y368701I0J-3937D01*
G01X-181103Y409449D02*
X-204725D01*
G01X-212599Y372638D02*
X-224410D01*
G01X-208662Y405512D02*
Y376575D01*
G01X-232284Y417323D02*
X-181103D01*
G01X-232284D02*
X-181103D01*
G01X-236221Y716536D02*
G03X-232284Y712599I3937J0D01*
G01X-224410Y724410D02*
G03X-220473Y720473I3937J0D01*
G01X-236221Y716536D02*
G03X-232284Y712599I3937J0D01*
G01X-220473Y720473D02*
X-96418D01*
G01Y712599D02*
X-232284D01*
G01X-96418D02*
X-232284D01*
G01X-224410Y933071D02*
Y724410D01*
G01X-236221Y921260D02*
Y716536D01*
G01Y921260D02*
G03X-240158Y925197I-3937J0D01*
G01X-236221Y921260D02*
G03X-240158Y925197I-3937J0D01*
G01X759843Y733661D02*
G02X763780Y737598I3937J0D01*
G01X789764D01*
Y781693D01*
X765945D01*
G02Y789173I0J3740D01*
G01X789764D01*
Y817520D01*
X763780D01*
G02X759843Y821457I0J3937D01*
G01Y921260D01*
G03X755906Y925197I-3937J0D01*
G01X82677D01*
G03X78740Y921260I0J-3937D01*
G01Y791339D01*
G02X74803Y787402I-3937J0D01*
G01X3937D01*
G03X0Y783465I0J-3937D01*
G01Y511811D01*
G02X-3937Y507874I-3937J0D01*
G01X-55118D01*
G03X-59055Y503937I0J-3937D01*
G01Y346457D01*
G02X-62992Y342520I-3937J0D01*
G01X-139803D01*
G03X-143740Y338583I0J-3937D01*
G01Y216535D01*
G03X-139803Y212598I3937J0D01*
G01X-3937D01*
G02X0Y208661I0J-3937D01*
G01Y3937D01*
G03X3937Y0I3937J0D01*
G01X755906D01*
G03X759843Y3937I0J3937D01*
G01Y324213D01*
G02X763780Y328150I3937J0D01*
G01X789764D01*
Y372244D01*
X765945D01*
G02Y379724I0J3740D01*
G01X789764D01*
Y660039D01*
X763780D01*
G02X759843Y663976I0J3937D01*
G01Y733661D01*
G01X-143740Y216536D02*
G03X-139803Y212599I3937J0D01*
G01X-143740Y262205D02*
G03X-151614I-3937J0D01*
G01X-143740Y216536D02*
G03X-139803Y212599I3937J0D01*
G01X-151614Y216536D02*
G03X-139803Y204725I11811J0D01*
G01X-143740Y262205D02*
Y292914D01*
G01Y338583D02*
Y216536D01*
G01Y338583D02*
Y216536D01*
G01X-151614D02*
Y262205D01*
G01X-139803Y212599D02*
X-3937D01*
G01X-139803D02*
X-3937D01*
G01X-15748Y204725D02*
X-139803D01*
G01Y342520D02*
G03X-143740Y338583I0J-3937D01*
G01X-139803Y342520D02*
G03X-143740Y338583I0J-3937D01*
G01X-139803Y350394D02*
G03X-151614Y338583I0J-11811D01*
G01Y292914D02*
G03X-143740I3937J0D01*
G01X-151614D02*
Y338583D01*
G01X-62992Y342520D02*
X-139803D01*
G01X-62992D02*
X-139803D01*
G01X-181103Y409449D02*
G03X-169292Y421260I0J11811D01*
G01X-139803Y350394D02*
X-70866D01*
G01X-177166Y467717D02*
G03X-169292I3937J0D01*
G01X-181103Y417323D02*
G03X-177166Y421260I0J3937D01*
G01X-169292Y437008D02*
G03X-177166I-3937J0D01*
G01X-181103Y417323D02*
G03X-177166Y421260I0J3937D01*
G01X-169292Y437008D02*
Y421260D01*
G01Y570866D02*
Y467717D01*
G01X-177166Y421260D02*
Y578740D01*
G01Y421260D02*
Y578740D01*
G01Y467717D02*
Y437008D01*
G01X-173229Y582677D02*
G03X-177166Y578740I0J-3937D01*
G01X-165355Y574803D02*
G03X-169292Y570866I0J-3937D01*
G01X-173229Y582677D02*
G03X-177166Y578740I0J-3937D01*
G01X-173229Y582677D02*
X-96418D01*
G01X-173229D02*
X-96418D01*
G01Y574803D02*
X-165355D01*
G01X-62992Y342520D02*
G03X-59055Y346457I0J3937D01*
G01X-62992Y342520D02*
G03X-59055Y346457I0J3937D01*
G01X-70866Y350394D02*
G03X-66929Y354331I0J3937D01*
G01D02*
Y457481D01*
G01Y488189D02*
G03X-59055I3937J0D01*
G01Y457481D02*
G03X-66929I-3937J0D01*
G01X-55118Y515748D02*
G03X-66929Y503937I0J-11811D01*
G01Y488189D02*
Y503937D01*
G01X-96418Y582677D02*
G03X-92481Y586615I0J3937D01*
G01X-96418Y582677D02*
G03X-92481Y586615I0J3937D01*
G01X-96418Y574803D02*
G03X-84607Y586615I0J11811D01*
G01Y632284D02*
Y586615D01*
G01X-92481D02*
Y708662D01*
G01Y586615D02*
Y708662D01*
G01Y662992D02*
G03X-84607I3937J0D01*
G01Y632284D02*
G03X-92481I-3937J0D01*
G01X-84607Y708662D02*
Y662992D01*
G01X-92481D02*
Y632284D01*
G01Y708662D02*
G03X-96418Y712599I-3937J0D01*
G01X-92481Y708662D02*
G03X-96418Y712599I-3937J0D01*
G01X-84607Y708662D02*
G03X-96418Y720473I-11811J0D01*
G01X-11811Y-3937D02*
G03X-7874Y-7874I3937J0D01*
G01X31496D02*
X-7874D01*
G01X0Y3937D02*
G03X3937Y0I3937J0D01*
G01X0Y3937D02*
G03X3937Y0I3937J0D01*
G01X0Y3937D02*
Y208662D01*
G01X-11811Y-3937D02*
Y200788D01*
G01X755905Y0D02*
X3937D01*
G01X755905D02*
X3937D01*
G01X-11811Y200788D02*
G03X-15748Y204725I-3937J0D01*
G01X0Y208662D02*
G03X-3937Y212599I-3937J0D01*
G01X0Y208662D02*
G03X-3937Y212599I-3937J0D01*
G01X-59055Y503937D02*
Y346457D01*
G01Y503937D02*
Y346457D01*
G01Y488189D02*
Y457481D01*
G01X-23622Y552559D02*
G03X-27559Y548622I0J-3937D01*
G01X-11811Y552559D02*
G03X-7874Y556496I0J3937D01*
G01X-3937Y507874D02*
G03X0Y511811I0J3937D01*
G01X-3937Y507874D02*
G03X0Y511811I0J3937D01*
G01X-55118Y507874D02*
G03X-59055Y503937I0J-3937D01*
G01X-31496Y515748D02*
G03X-27559Y519685I0J3937D01*
G01X-55118Y507874D02*
G03X-59055Y503937I0J-3937D01*
G01X-23622Y552559D02*
X-11811D01*
G01X0Y511811D02*
Y783465D01*
G01X-27559Y519685D02*
Y548622D01*
G01X-55118Y515748D02*
X-31496D01*
G01X-3937Y507874D02*
X-55118D01*
G01X-3937D02*
X-55118D01*
G01X-7874Y556496D02*
Y783465D01*
G01X3937Y787402D02*
G03X0Y783465I0J-3937D01*
G01X3937Y787402D02*
G03X0Y783465I0J-3937D01*
G01X3937Y795276D02*
G03X-7874Y783465I0J-11811D01*
G01X3937Y795276D02*
X8661D01*
G01X3937Y787402D02*
X74803D01*
G01X3937D02*
X74803D01*
G01X62204Y0D02*
G03Y-7874I0J-3937D01*
G01X31496D02*
G03Y0I0J3937D01*
G01X267716Y-7874D02*
X62204D01*
G01Y0D02*
X31496D01*
G01X74803Y787402D02*
G03X78740Y791339I0J3937D01*
G01X30315Y795276D02*
G03X34252Y799213I0J3937D01*
G01X24409Y795276D02*
G03Y787402I0J-3937D01*
G01X8661D02*
G03Y795276I0J3937D01*
G01X74803Y787402D02*
G03X78740Y791339I0J3937D01*
G01X24409Y795276D02*
X30315D01*
G01X24409Y787402D02*
X8661D01*
G01X34252Y799213D02*
Y889666D01*
G01X38189Y893603D02*
G03X34252Y889666I0J-3937D01*
G01X66929Y893603D02*
G03X70866Y897540I0J3937D01*
G01X38189Y893603D02*
X66929D01*
G01X70866Y897540D02*
Y929134D01*
G01X74803Y933071D02*
G03X70866Y929134I0J-3937D01*
G01X74803Y933071D02*
X88582D01*
G01X78740Y791339D02*
Y921260D01*
G01Y791339D02*
Y921260D01*
G01X119291Y933071D02*
G03Y925197I0J-3937D01*
G01X82677D02*
G03X78740Y921260I0J-3937D01*
G01X88582Y925197D02*
G03Y933071I0J3937D01*
G01X82677Y925197D02*
G03X78740Y921260I0J-3937D01*
G01X119291Y933071D02*
X305118D01*
G01X82677Y925197D02*
X755905D01*
G01X82677D02*
X755905D01*
G01X119291D02*
X88582D01*
G01X267716Y-7874D02*
G03Y0I0J3937D01*
G01X298425D02*
X267716D01*
G01X298425D02*
G03Y-7874I0J-3937D01*
G01X483071D02*
X298425D01*
G01X335827Y933071D02*
G03Y925197I0J-3937D01*
G01X305118D02*
G03Y933071I0J3937D01*
G01X335827D02*
X522441D01*
G01X335827Y925197D02*
X305118D01*
G01X483071Y-7874D02*
G03Y0I0J3937D01*
G01X513779D02*
X483071D01*
G01X513779D02*
G03Y-7874I0J-3937D01*
G01X719291D02*
X513779D01*
G01X553149Y933071D02*
G03Y925197I0J-3937D01*
G01X522441D02*
G03Y933071I0J3937D01*
G01X553149D02*
X719291D01*
G01X553149Y925197D02*
X522441D01*
G01X763779Y-7874D02*
G03X767716Y-3937I0J3937D01*
G01X719291Y-7874D02*
G03Y0I0J3937D01*
G01X750000D02*
G03Y-7874I0J-3937D01*
G01X763779D02*
X750000D01*
G01X755905Y0D02*
G03X759842Y3937I0J3937D01*
G01X755905Y0D02*
G03X759842Y3937I0J3937D01*
G01X767716Y185827D02*
Y-3937D01*
G01X759842Y3937D02*
Y324213D01*
G01X750000Y0D02*
X719291D01*
G01X767716Y185827D02*
G03X759842I-3937J0D01*
G01Y216536D02*
Y185827D01*
G01Y216536D02*
G03X767716I3937J0D01*
G01Y316339D02*
Y216536D01*
G01X771653Y320276D02*
G03X767716Y316339I0J-3937D01*
G01X763779Y328150D02*
G03X759842Y324213I0J-3937D01*
G01X793307Y328150D02*
X763779D01*
G01X791338Y320276D02*
X771653D01*
G01X765945Y379725D02*
G03Y372244I0J-3741D01*
G01X793307Y379725D02*
X765945D01*
G01X793307Y372244D02*
X765945D01*
G01X759842Y663977D02*
G03X763779Y660040I3937J0D01*
G01X759842Y663977D02*
Y733662D01*
G01X793307Y660040D02*
X763779D01*
G01Y737599D02*
G03X759842Y733662I0J-3937D01*
G01X793307Y737599D02*
X763779D01*
G01X765945Y789174D02*
G03Y781693I0J-3740D01*
G01X767716Y829331D02*
G03X771653Y825394I3937J0D01*
G01X759842Y821457D02*
G03X763779Y817520I3937J0D01*
G01X767716Y855118D02*
Y829331D01*
G01X759842Y921260D02*
Y821457D01*
G01X771653Y825394D02*
X791338D01*
G01X793307Y817520D02*
X763779D01*
G01X793307Y789174D02*
X765945D01*
G01X793307Y781693D02*
X765945D01*
G01X767716Y855118D02*
G03X759842I-3937J0D01*
G01Y885827D02*
G03X767716I3937J0D01*
G01Y929134D02*
Y885827D01*
G01X759842D02*
Y855118D01*
G01Y921260D02*
G03X755905Y925197I-3937J0D01*
G01X767716Y929134D02*
G03X763779Y933071I-3937J0D01*
G01X750000D02*
G03Y925197I0J-3937D01*
G01X719291D02*
G03Y933071I0J3937D01*
G01X759842Y921260D02*
G03X755905Y925197I-3937J0D01*
G01X750000Y933071D02*
X763779D01*
G01X750000Y925197D02*
X719291D01*
G01X791338Y-35433D02*
G03X795275Y-31496I0J3937D01*
G01D02*
Y316339D01*
G01D02*
G03X791338Y320276I-3937J0D01*
G01X795275Y370276D02*
Y330118D01*
G01D02*
X793307Y328150D01*
G01X795275Y658071D02*
Y381693D01*
G01D02*
X793307Y379725D01*
G01X795275Y370276D02*
X793307Y372244D01*
G01X795275Y658071D02*
X793307Y660040D01*
G01X795275Y779725D02*
Y739567D01*
G01D02*
X793307Y737599D01*
G01X791338Y825394D02*
G03X795275Y829331I0J3937D01*
G01D02*
Y956693D01*
G01Y815552D02*
Y791142D01*
G01Y815552D02*
X793307Y817520D01*
G01X795275Y779725D02*
X793307Y781693D01*
G01X795275Y791142D02*
X793307Y789174D01*
G01X795275Y956693D02*
G03X791338Y960630I-3937J0D01*
M02*
